G04 ================== begin FILE IDENTIFICATION RECORD ==================*
G04 Layout Name:  D:/<user>/Wistron_project/16317-1/gbr/16317-1.brd*
G04 Film Name:    L3*
G04 File Format:  Gerber RS274X*
G04 File Origin:  Cadence Allegro 16.5-S056*
G04 Origin Date:  Fri Jun 09 15:53:25 2017*
G04 *
G04 Layer:  VIA CLASS/L3*
G04 Layer:  PIN/L3*
G04 Layer:  ETCH/L3*
G04 Layer:  DRAWING FORMAT/LAYER_PCB_STORY*
G04 Layer:  DRAWING FORMAT/LAYER_L3*
G04 *
G04 Offset:    (0.00 0.00)*
G04 Mirror:    No*
G04 Mode:      Positive*
G04 Rotation:  0*
G04 FullContactRelief:  No*
G04 UndefLineWidth:     6.00*
G04 ================== end FILE IDENTIFICATION RECORD ====================*
%FSLAX35Y35*MOIN*%
%IR0*IPPOS*OFA0.00000B0.00000*MIA0B0*SFA1.00000B1.00000*%
%ADD14C,.03*%
%ADD11C,.022*%
%ADD13C,.034*%
%ADD10C,.028*%
%ADD12C,.056*%
%ADD15C,.048*%
%ADD16C,.01*%
%ADD17C,.02*%
%ADD18C,.04*%
%ADD19C,.06*%
%ADD20C,.006*%
%ADD21C,.00575*%
%ADD25C,.05204*%
%ADD24C,.04404*%
%ADD22C,.04604*%
%ADD23O,.56122X.79744*%
G75*
%LPD*%
G75*
G36*
G01X787402Y192768D02*
G03X780461Y185827I0J-6941D01*
G01Y3937D01*
G02X779528Y3004I-933J0D01*
G01X3937D01*
G02X3004Y3937I0J933D01*
G01Y1456693D01*
G02X3937Y1457626I933J0D01*
G01X7874D01*
G03X14815Y1464567I0J6941D01*
G01Y1515748D01*
G02X15748Y1516681I933J0D01*
G01X60039D01*
G02X60972Y1515748I0J-933D01*
G01Y1509055D01*
G03X67913Y1502114I6941J0D01*
G01X93504D01*
G03X100445Y1509055I0J6941D01*
G01Y1515748D01*
G02X101378Y1516681I933J0D01*
G01X280709D01*
G02X281642Y1515748I0J-933D01*
G01Y1500000D01*
G03X288583Y1493059I6941J0D01*
G01X493307D01*
G03X500248Y1500000I0J6941D01*
G01Y1515748D01*
G02X501181Y1516681I933J0D01*
G01X680512D01*
G02X681445Y1515748I0J-933D01*
G01Y1509055D01*
G03X688386Y1502114I6941J0D01*
G01X713976D01*
G03X720917Y1509055I0J6941D01*
G01Y1515748D01*
G02X721850Y1516681I933J0D01*
G01X775591D01*
G02X776524Y1515748I0J-933D01*
G01Y1500000D01*
G03X783465Y1493059I6941J0D01*
G01X988189D01*
G03X995130Y1500000I0J6941D01*
G01Y1515748D01*
G02X996063Y1516681I933J0D01*
G01X1059198D01*
G02X1059856Y1516408I-1J-933D01*
G01X1069361Y1506903D01*
G02X1069634Y1506245I-660J-660D01*
G01Y1421260D01*
G03X1076575Y1414319I6941J0D01*
G01X1085630D01*
G03X1092571Y1421260I0J6941D01*
G01Y1506245D01*
G02X1092844Y1506903I933J-1D01*
G01X1102349Y1516408D01*
G02X1103007Y1516681I659J-660D01*
G01X1207283D01*
G02X1208216Y1515748I0J-933D01*
G01Y1509055D01*
G03X1215157Y1502114I6941J0D01*
G01X1240748D01*
G03X1247689Y1509055I0J6941D01*
G01Y1515748D01*
G02X1248622Y1516681I933J0D01*
G01X1427953D01*
G02X1428886Y1515748I0J-933D01*
G01Y1500000D01*
G03X1435827Y1493059I6941J0D01*
G01X1640551D01*
G03X1647492Y1500000I0J6941D01*
G01Y1515748D01*
G02X1648425Y1516681I933J0D01*
G01X1827756D01*
G02X1828689Y1515748I0J-933D01*
G01Y1509055D01*
G03X1835630Y1502114I6941J0D01*
G01X1861220D01*
G03X1868161Y1509055I0J6941D01*
G01Y1515748D01*
G02X1869094Y1516681I933J0D01*
G01X1919094D01*
G02X1920027Y1515748I0J-933D01*
G01Y1464567D01*
G03X1926967Y1457626I6941J0D01*
G01X1930906D01*
G02X1931839Y1456693I0J-933D01*
G01Y1342561D01*
X1926843D01*
Y1452631D01*
G02X1915031Y1464567I125J11936D01*
G01Y1511685D01*
X1873157D01*
Y1509055D01*
G02X1861220Y1497118I-11937J0D01*
G01X1835630D01*
G02X1823693Y1509055I0J11937D01*
G01Y1511685D01*
X1652488D01*
Y1500000D01*
G02X1640551Y1488063I-11937J0D01*
G01X1435827D01*
G02X1423890Y1500000I0J11937D01*
G01Y1511685D01*
X1252685D01*
Y1509055D01*
G02X1240748Y1497118I-11937J0D01*
G01X1215157D01*
G02X1203220Y1509055I0J11937D01*
G01Y1511685D01*
X1104691D01*
X1097567Y1504561D01*
Y1421260D01*
G02X1085630Y1409323I-11937J0D01*
G01X1076575D01*
G02X1064638Y1421260I0J11937D01*
G01Y1504561D01*
X1057514Y1511685D01*
X1000126D01*
Y1500000D01*
G02X988189Y1488063I-11937J0D01*
G01X783465D01*
G02X771528Y1500000I0J11937D01*
G01Y1511685D01*
X725913D01*
Y1509055D01*
G02X713976Y1497118I-11937J0D01*
G01X688386D01*
G02X676449Y1509055I0J11937D01*
G01Y1511685D01*
X505244D01*
Y1500000D01*
G02X493307Y1488063I-11937J0D01*
G01X288583D01*
G02X276646Y1500000I0J11937D01*
G01Y1511685D01*
X105441D01*
Y1509055D01*
G02X93504Y1497118I-11937J0D01*
G01X67913D01*
G02X55976Y1509055I0J11937D01*
G01Y1511685D01*
X19811D01*
Y1464567D01*
G02X8000Y1452631I-11937J0D01*
G01Y8000D01*
X775465D01*
Y185827D01*
G02X787402Y197764I11937J0D01*
G01X806961D01*
Y244095D01*
G02X818897Y256031I11937J-1D01*
G01X832344D01*
G03X835374I1515J2237D01*
G01X846517D01*
G03X849547I1515J2237D01*
G01X860690D01*
G03X863720I1515J2237D01*
G01X874863D01*
G03X877893I1515J2237D01*
G01X891245D01*
Y251035D01*
X818897D01*
G03X811957Y244095I1J-6941D01*
G01Y193701D01*
G02X811024Y192768I-933J0D01*
G01X787402D01*
G37*
G36*
G01X164074Y1417434D02*
X160508Y1421000D01*
X142046D01*
X142009Y1421152D01*
G03X139581Y1422894I-2235J-552D01*
G01X139488Y1422886D01*
X132874Y1429500D01*
Y1444400D01*
X122374Y1454900D01*
X114074D01*
X109174Y1459800D01*
X105492D01*
G02X105282Y1460540I0J400D01*
G03X102866I-1208J1960D01*
G02X102656Y1459800I-210J-340D01*
G01X101574D01*
X100474Y1460900D01*
Y1480500D01*
X101734Y1481760D01*
Y1493514D01*
X110362Y1502142D01*
X127232D01*
X158874Y1470500D01*
Y1456048D01*
G02X158341Y1455671I-400J0D01*
G03Y1451329I-767J-2171D01*
G02X158874Y1450952I133J-377D01*
G01Y1441000D01*
X162874Y1437000D01*
X182374D01*
X187874Y1431500D01*
Y1422500D01*
X186374Y1421000D01*
X186269D01*
X182703Y1417434D01*
X164074D01*
G37*
G36*
G01X286500Y1364000D02*
X288500Y1366000D01*
X398500D01*
X401250Y1363250D01*
Y1308750D01*
X397500Y1305000D01*
X288500D01*
X286500Y1307000D01*
Y1364000D01*
G37*
G36*
G01X424800Y69200D02*
X422500Y71500D01*
Y74500D01*
X423500Y75500D01*
X429500D01*
X440500Y86500D01*
Y107000D01*
X431500Y116000D01*
Y120543D01*
G03Y124171I-1417J1814D01*
G01Y135500D01*
X432500Y136500D01*
X442500D01*
X443500Y135500D01*
Y134140D01*
G03Y131860I2000J-1140D01*
G01Y128015D01*
G02X442834Y127717I-400J0D01*
G03Y124283I-1534J-1717D01*
G02X443500Y123985I266J-298D01*
G01Y119500D01*
X450000Y113000D01*
Y92400D01*
G03Y89800I1900J-1300D01*
G01Y77900D01*
X441300Y69200D01*
X424800D01*
G37*
G36*
G01X599811Y1288250D02*
X597750Y1290311D01*
Y1302811D01*
X595837Y1304724D01*
X536520D01*
G02X536396Y1305504I0J400D01*
G03X531496Y1336222I-4900J14968D01*
G01X511496D01*
G03X506596Y1305504I0J-15750D01*
G02X506472Y1304724I-124J-380D01*
G01X410337D01*
X405252Y1309809D01*
Y1362691D01*
X408750Y1366189D01*
Y1433798D01*
X409952Y1435000D01*
X430000D01*
X441500Y1423500D01*
X484200D01*
X497450Y1410250D01*
X632250D01*
Y1295750D01*
X621689D01*
X619750Y1293811D01*
Y1288811D01*
X619189Y1288250D01*
X599811D01*
G37*
G36*
G01X498800Y1454100D02*
Y1467300D01*
X507000Y1475500D01*
X532100D01*
X538000Y1469600D01*
Y1458000D01*
X525211Y1445211D01*
X507689D01*
X498800Y1454100D01*
G37*
G36*
G01X655100Y1295750D02*
Y1410250D01*
X800721D01*
X802808Y1408162D01*
Y1295750D01*
X655100D01*
G37*
G36*
G01X933100Y251100D02*
X932500Y251700D01*
Y286400D01*
X935300Y289200D01*
Y405700D01*
X886900Y454100D01*
Y614700D01*
X883500Y618100D01*
Y627678D01*
G02X884033Y628055I400J0D01*
G03Y632395I768J2170D01*
G02X883500Y632772I-133J377D01*
G01Y813525D01*
X883501Y813537D01*
G03Y814089I-2285J276D01*
G01X883500Y814101D01*
Y837422D01*
G03X884002Y838962I-1798J1438D01*
G01Y852157D01*
X883500Y852659D01*
Y874820D01*
G02X884016Y875203I400J0D01*
G03Y879609I668J2203D01*
G02X883500Y879992I-116J383D01*
G01Y883944D01*
X883650Y883983D01*
G03X882288Y888375I-578J2228D01*
G01X882168Y888332D01*
X880035Y890465D01*
X880071Y890581D01*
G03X877181Y893471I-2194J696D01*
G01X877065Y893435D01*
X856250Y914250D01*
Y1146250D01*
X822500Y1180000D01*
Y1291698D01*
G03X824048Y1295704I0J2302D01*
G02Y1296296I269J296D01*
G03X820952I-1548J1704D01*
G02Y1295704I-269J-296D01*
G03X820874Y1295630I1545J-1707D01*
G02X820309I-282J283D01*
G01X817964Y1297976D01*
Y1396280D01*
X818949Y1397265D01*
X825735D01*
X834816Y1388184D01*
X952316D01*
X953300Y1387200D01*
Y1364100D01*
X951900Y1362700D01*
X942800D01*
X939900Y1359800D01*
Y1353200D01*
X941404Y1351696D01*
X952698D01*
X952899Y1351495D01*
Y1329601D01*
X954500Y1328000D01*
X963100D01*
X965900Y1325200D01*
Y1270900D01*
X1079200Y1157600D01*
Y252200D01*
X1078100Y251100D01*
X933100D01*
G37*
G36*
G01X1023718Y1301518D02*
X1021100Y1298900D01*
X983900D01*
X982600Y1300200D01*
Y1356000D01*
X986900Y1360300D01*
X986918D01*
Y1393340D01*
X988829Y1395251D01*
X1016656D01*
X1023718Y1388189D01*
Y1301518D01*
G37*
G36*
G01X1062059Y243000D02*
X1067055D01*
Y197764D01*
X1220472D01*
G02X1232409Y185827I0J-11937D01*
G01Y8000D01*
X1926843D01*
Y1341021D01*
X1931839D01*
Y3937D01*
G02X1930906Y3004I-933J0D01*
G01X1228346D01*
G02X1227413Y3937I0J933D01*
G01Y185827D01*
G03X1220472Y192768I-6941J0D01*
G01X1062992D01*
G02X1062059Y193701I0J933D01*
G01Y243000D01*
G37*
G36*
G01X1143782Y1177500D02*
X1140727Y1180555D01*
Y1327860D01*
X1096909Y1371678D01*
Y1377261D01*
G02X1097576Y1377559I400J0D01*
G03Y1380987I1536J1714D01*
G02X1096909Y1381285I-267J298D01*
G01Y1385261D01*
G02X1097576Y1385559I400J0D01*
G03Y1388987I1536J1714D01*
G02X1096909Y1389285I-267J298D01*
G01Y1393355D01*
X1107566Y1404012D01*
G02X1108243Y1403662I283J-283D01*
G03X1110123Y1405542I2269J-389D01*
G02X1109773Y1406219I-67J394D01*
G01X1113448Y1409894D01*
X1117586D01*
X1117712Y1410021D01*
X1160793D01*
X1169180Y1401634D01*
Y1399169D01*
X1169015Y1399140D01*
G03Y1394606I397J-2267D01*
G01X1169180Y1394577D01*
Y1180619D01*
X1166061Y1177500D01*
X1143782D01*
G37*
%LPC*%
G75*
G36*
G01X155293Y1432532D02*
G03X155337Y1433211I-188J353D01*
G02X157755Y1433053I1337J1874D01*
G03X157711Y1432374I188J-353D01*
G02X155293Y1432532I-1337J-1874D01*
G37*
G36*
G01X824048Y1371796D02*
G03Y1371204I269J-296D01*
G02X820952I-1548J-1704D01*
G03Y1371796I-269J296D01*
G02X824048I1548J1704D01*
G37*
G36*
G01Y1333296D02*
G03Y1332704I269J-296D01*
G02X820952I-1548J-1704D01*
G03Y1333296I-269J296D01*
G02X824048I1548J1704D01*
G37*
G36*
G01X945204Y1234548D02*
G03X945796I296J269D01*
G02X949204I1704J-1548D01*
G03X949796I296J269D01*
G02X953204I1704J-1548D01*
G03X953796I296J269D01*
G02X957204I1704J-1548D01*
G03X957796I296J269D01*
G02X961204I1704J-1548D01*
G03X961796I296J269D01*
G02X965204I1704J-1548D01*
G03X965796I296J269D01*
G02Y1231452I1704J-1548D01*
G03X965204I-296J-269D01*
G02X961796I-1704J1548D01*
G03X961204I-296J-269D01*
G02X957796I-1704J1548D01*
G03X957204I-296J-269D01*
G02X953796I-1704J1548D01*
G03X953204I-296J-269D01*
G02X949796I-1704J1548D01*
G03X949204I-296J-269D01*
G02X945796I-1704J1548D01*
G03X945204I-296J-269D01*
G02Y1234548I-1704J1548D01*
G37*
G36*
G01X893192Y1201358D02*
G03X892793Y1200994I-1J-400D01*
G02X890508Y1203502I-2293J206D01*
G03X890907Y1203866I1J400D01*
G02X893192Y1201358I2293J-206D01*
G37*
G36*
G01X984048Y1199296D02*
G03Y1198704I269J-296D01*
G02X980952I-1548J-1704D01*
G03Y1199296I-269J296D01*
G02Y1202704I1548J1704D01*
G03Y1203296I-269J296D01*
G02Y1206704I1548J1704D01*
G03Y1207296I-269J296D01*
G02Y1210704I1548J1704D01*
G03Y1211296I-269J296D01*
G02Y1214704I1548J1704D01*
G03Y1215296I-269J296D01*
G02Y1218704I1548J1704D01*
G03Y1219296I-269J296D01*
G02Y1222704I1548J1704D01*
G03Y1223296I-269J296D01*
G02X984048I1548J1704D01*
G03Y1222704I269J-296D01*
G02Y1219296I-1548J-1704D01*
G03Y1218704I269J-296D01*
G02Y1215296I-1548J-1704D01*
G03Y1214704I269J-296D01*
G02Y1211296I-1548J-1704D01*
G03Y1210704I269J-296D01*
G02Y1207296I-1548J-1704D01*
G03Y1206704I269J-296D01*
G02Y1203296I-1548J-1704D01*
G03Y1202704I269J-296D01*
G02Y1199296I-1548J-1704D01*
G37*
G36*
G01X1027104Y1120431D02*
G03X1027178Y1120993I-243J318D01*
G02X1030396Y1120570I1822J1407D01*
G03X1030322Y1120008I243J-318D01*
G02X1027104Y1120431I-1822J-1407D01*
G37*
G36*
G01X952370Y1113627D02*
G03X951630I-370J-152D01*
G02X947213Y1114759I-2130J873D01*
G03X946843Y1115203I-397J45D01*
G02X945296Y1115952I157J2297D01*
G03X944704I-296J-269D01*
G02Y1119048I-1704J1548D01*
G03X945296I296J269D01*
G02X948917Y1118775I1704J-1548D01*
G03X949583I333J221D01*
G02X953630Y1118373I1917J-1275D01*
G03X954370I370J152D01*
G02X958417Y1118775I2130J-873D01*
G03X959083I333J221D01*
G02Y1116225I1917J-1275D01*
G03X958417I-333J-221D01*
G02X957075Y1115271I-1917J1275D01*
G03X956779Y1114827I100J-387D01*
G02X952370Y1113627I-2279J-327D01*
G37*
G36*
G01X897383Y979270D02*
G03X897679Y978752I379J-127D01*
G02X895666Y974783I-479J-2252D01*
G03X895134I-266J-298D01*
G02X892066I-1534J1717D01*
G03X891534I-266J-298D01*
G02X888466I-1534J1717D01*
G03X887934I-266J-298D01*
G02X885612Y978663I-1534J1717D01*
G03X885849Y979181I-137J376D01*
G02X889534Y981717I2151J819D01*
G03X890066I266J298D01*
G02X893134I1534J-1717D01*
G03X893666I266J298D01*
G02X897383Y979270I1534J-1717D01*
G37*
G36*
G01X1026928Y946731D02*
G03X1026425Y946316I-104J-386D01*
G02X1024725Y948375I-2296J-164D01*
G03X1025228Y948790I104J386D01*
G02X1028088Y951186I2296J164D01*
G03X1028582Y951629I98J388D01*
G02X1030298Y949714I2280J317D01*
G03X1029804Y949271I-98J-388D01*
G02X1026928Y946731I-2280J-317D01*
G37*
G36*
G01X925343Y921195D02*
G03X924677I-333J-221D01*
G02X920660Y921527I-1917J1275D01*
G03X920010Y921644I-365J-164D01*
G02X916262Y922330I-1641J1614D01*
G03X915646Y922482I-366J-161D01*
G02X912007Y923606I-1438J1797D01*
G03X911348Y923779I-383J-117D01*
G02X911961Y926118I-1588J1666D01*
G03X912620Y925945I383J117D01*
G02X916315Y925207I1588J-1666D01*
G03X916931Y925055I366J161D01*
G02X920469Y924201I1438J-1797D01*
G03X921119Y924084I365J164D01*
G02X924677Y923745I1641J-1614D01*
G03X925343I333J221D01*
G02Y921195I1917J-1275D01*
G37*
G36*
G01X1013414Y896662D02*
G03X1013385Y897265I-277J289D01*
G02X1016400Y897413I1422J1810D01*
G03X1016429Y896810I277J-289D01*
G02X1013414Y896662I-1422J-1810D01*
G37*
G36*
G01X1026705Y895349D02*
G03X1026732Y894762I285J-281D01*
G02X1023611Y894616I-1481J-1762D01*
G03X1023584Y895203I-285J281D01*
G02X1026705Y895349I1481J1762D01*
G37*
G36*
G01X987953Y881451D02*
G03X987331I-311J-251D01*
G02Y884349I-1789J1449D01*
G03X987953I311J251D01*
G02X991531I1789J-1449D01*
G03X992153I311J251D01*
G02Y881451I1789J-1449D01*
G03X991531I-311J-251D01*
G02X987953I-1789J1449D01*
G37*
G36*
G01X978502Y885039D02*
G03X979124Y884787I393J76D01*
G02X978182Y882461I1318J-1887D01*
G03X977560Y882713I-393J-76D01*
G02X974453Y883151I-1318J1887D01*
G03X973831I-311J-251D01*
G02Y886049I-1789J1449D01*
G03X974453I311J251D01*
G02X978502Y885039I1789J-1449D01*
G37*
G36*
G01X892528Y859757D02*
G03X891906I-311J-251D01*
G02X888668Y862995I-1789J1449D01*
G03Y863617I-251J311D01*
G02X891906Y866855I1449J1789D01*
G03X892528I311J251D01*
G02X895766Y863617I1789J-1449D01*
G03Y862995I251J-311D01*
G02X892528Y859757I-1449J-1789D01*
G37*
G36*
G01X913663Y856145D02*
G03X912997I-333J-221D01*
G02Y858695I-1917J1275D01*
G03X913663I333J221D01*
G02X917533Y858639I1917J-1275D01*
G03X918212Y858641I339J212D01*
G02X922087Y858705I1958J-1211D01*
G03X922753I333J221D01*
G02Y856155I1917J-1275D01*
G03X922087I-333J-221D01*
G02X918217Y856211I-1917J1275D01*
G03X917538Y856209I-339J-212D01*
G02X913663Y856145I-1958J1211D01*
G37*
G36*
G01X945370Y840550D02*
G03X945265Y840022I238J-322D01*
G02X941924Y840683I-1971J-1189D01*
G03X942029Y841211I-238J322D01*
G02X941930Y841393I1971J1190D01*
G03X941570I-180J-87D01*
G02X941417Y843675I-2070J1007D01*
G03X942083I333J221D01*
G02X945917I1917J-1275D01*
G03X946583I333J221D01*
G02X950417I1917J-1275D01*
G03X951083I333J221D01*
G02X954917I1917J-1275D01*
G03X955583I333J221D01*
G02X959417I1917J-1275D01*
G03X960083I333J221D01*
G02Y841125I1917J-1275D01*
G03X959417I-333J-221D01*
G02X955583I-1917J1275D01*
G03X954917I-333J-221D01*
G02X951083I-1917J1275D01*
G03X950417I-333J-221D01*
G02X946583I-1917J1275D01*
G03X945917I-333J-221D01*
G02X945370Y840550I-1916J1275D01*
G37*
G36*
G01X933165Y822953D02*
G03X933773Y822939I310J253D01*
G02X933700Y819947I1712J-1539D01*
G03X933092Y819961I-310J-253D01*
G02X933165Y822953I-1712J1539D01*
G37*
G36*
G01X904343Y814769D02*
G03X904877Y814691I310J253D01*
G02X904383Y811328I1289J-1907D01*
G03X903849Y811406I-310J-253D01*
G02X904343Y814769I-1289J1907D01*
G37*
G36*
G01X915477Y809090D02*
G03X914915Y809006I-239J-321D01*
G02X914437Y812211I-1856J1361D01*
G03X914999Y812295I239J321D01*
G02X918461Y812583I1856J-1361D01*
G03X919082Y812661I279J287D01*
G02X921991Y813563I1966J-1198D01*
G03X922500Y813725I164J365D01*
G02X923540Y810458I1984J-1167D01*
G03X923031Y810296I-164J-365D01*
G02X919441Y809814I-1984J1167D01*
G03X918820Y809736I-279J-287D01*
G02X915477Y809090I-1965J1198D01*
G37*
G36*
G01X907277Y786458D02*
G03X906786Y786075I-91J-389D01*
G02X905007Y788351I-2302J34D01*
G03X905498Y788734I91J389D01*
G02X909930Y789574I2302J-34D01*
G03X910556Y789418I370J151D01*
G02X909900Y786776I1474J-1768D01*
G03X909274Y786932I-370J-151D01*
G02X907277Y786458I-1474J1768D01*
G37*
G36*
G01X1059013Y774315D02*
G03X1058987Y773662I217J-336D01*
G02X1055987Y773785I-1587J-2062D01*
G03X1056013Y774438I-217J336D01*
G02X1056160Y778667I1587J2062D01*
G03Y779333I-222J333D01*
G02Y783667I1440J2167D01*
G03Y784333I-222J333D01*
G02Y788667I1440J2167D01*
G03Y789333I-222J333D01*
G02Y793667I1440J2167D01*
G03Y794333I-222J333D01*
G02X1059680Y798063I1440J2167D01*
G03X1060320I320J240D01*
G02X1064480I2080J-1563D01*
G03X1065120I320J240D01*
G02X1068640Y794333I2080J-1563D01*
G03Y793667I222J-333D01*
G02Y789333I-1440J-2167D01*
G03Y788667I222J-333D01*
G02X1065120Y784937I-1440J-2167D01*
G03X1064480I-320J-240D01*
G02X1063840Y784333I-2080J1563D01*
G03Y783667I222J-333D01*
G02X1060320Y779937I-1440J-2167D01*
G03X1059680I-320J-240D01*
G02X1059040Y779333I-2080J1563D01*
G03Y778667I222J-333D01*
G02X1059013Y774315I-1440J-2167D01*
G37*
G36*
G01X902668Y775857D02*
G03X902895Y776340I-156J368D01*
G02X906004Y774883I2205J660D01*
G03X905777Y774400I156J-368D01*
G02X905160Y772074I-2205J-660D01*
G03X905150Y771505I276J-289D01*
G02X901912Y771566I-1650J-1605D01*
G03X901922Y772135I-276J289D01*
G02X902668Y775857I1650J1605D01*
G37*
G36*
G01X1019114Y765320D02*
G03X1018474I-320J-240D01*
G02X1014831Y768963I-2080J1563D01*
G03Y769603I-240J320D01*
G02Y773763I1563J2080D01*
G03Y774403I-240J320D01*
G02X1018474Y778046I1563J2080D01*
G03X1019114I320J240D01*
G02X1022757Y774403I2080J-1563D01*
G03Y773763I240J-320D01*
G02Y769603I-1563J-2080D01*
G03Y768963I240J-320D01*
G02X1019114Y765320I-1563J-2080D01*
G37*
G36*
G01X1040640Y764393D02*
G03X1040348Y763769I38J-398D01*
G02X1036046Y763759I-2148J-1469D01*
G03X1035698Y764383I-331J224D01*
G02X1034031Y769063I-104J2600D01*
G03Y769703I-240J320D01*
G02Y773863I1563J2080D01*
G03Y774503I-240J320D01*
G02X1037674Y778146I1563J2080D01*
G03X1038314I320J240D01*
G02X1041957Y774503I2080J-1563D01*
G03Y773863I240J-320D01*
G02Y769703I-1563J-2080D01*
G03Y769063I240J-320D01*
G02X1040640Y764393I-1563J-2080D01*
G37*
G36*
G01X976021Y561919D02*
G03X976018Y561306I256J-308D01*
G02X973059Y561321I-1488J-1756D01*
G03X973062Y561934I-256J308D01*
G02X976021Y561919I1488J1756D01*
G37*
G36*
G01X973384Y539151D02*
G03X974049Y539124I342J208D01*
G02X973946Y536569I1861J-1355D01*
G03X973281Y536596I-342J-208D01*
G02X973384Y539151I-1861J1355D01*
G37*
G36*
G01X993596Y528199D02*
G03X993025Y528191I-282J-284D01*
G02X992977Y531418I-1665J1589D01*
G03X993548Y531426I282J284D01*
G02X996792Y531512I1665J-1589D01*
G03X997338Y531510I274J291D01*
G02X997326Y528149I1567J-1686D01*
G03X996780Y528151I-274J-291D01*
G02X993596Y528199I-1567J1686D01*
G37*
G36*
G01X936774Y522121D02*
G03X936776Y521459I226J-330D01*
G02X934193Y521452I-1286J-1909D01*
G03X934191Y522114I-226J330D01*
G02X936774Y522121I1286J1909D01*
G37*
G36*
G01X1045739Y304430D02*
G03Y303839I270J-296D01*
G02X1040875I-2432J-2657D01*
G03Y304430I-270J295D01*
G02X1040876Y309745I2432J2657D01*
G03Y310335I-270J295D01*
G02X1045738I2431J2658D01*
G03Y309745I270J-295D01*
G02X1045739Y304430I-2431J-2658D01*
G37*
G36*
G01X1033141D02*
G03Y303839I270J-296D01*
G02X1028277I-2432J-2657D01*
G03Y304430I-270J295D01*
G02X1028278Y309745I2432J2657D01*
G03Y310335I-270J295D01*
G02X1033140I2431J2658D01*
G03Y309745I270J-295D01*
G02X1033141Y304430I-2431J-2658D01*
G37*
G36*
G01X1017392D02*
G03Y303839I270J-296D01*
G02X1012528I-2432J-2657D01*
G03Y304430I-270J295D01*
G02X1012529Y309745I2432J2657D01*
G03Y310335I-270J295D01*
G02X1017391I2431J2658D01*
G03Y309745I270J-295D01*
G02X1017392Y304430I-2431J-2658D01*
G37*
G36*
G01X1004794D02*
G03Y303839I270J-296D01*
G02X999930I-2432J-2657D01*
G03Y304430I-270J295D01*
G02X999931Y309745I2432J2657D01*
G03Y310335I-270J295D01*
G02X1004793I2431J2658D01*
G03Y309745I270J-295D01*
G02X1004794Y304430I-2431J-2658D01*
G37*
G36*
G01X989046D02*
G03Y303839I270J-296D01*
G02X984182I-2432J-2657D01*
G03Y304430I-270J295D01*
G02X984183Y309745I2432J2657D01*
G03Y310335I-270J295D01*
G02X989045I2431J2658D01*
G03Y309745I270J-295D01*
G02X989046Y304430I-2431J-2658D01*
G37*
G36*
G01X976447D02*
G03Y303839I270J-296D01*
G02X971583I-2432J-2657D01*
G03Y304430I-270J295D01*
G02X971584Y309745I2432J2657D01*
G03Y310335I-270J295D01*
G02X976446I2431J2658D01*
G03Y309745I270J-295D01*
G02X976447Y304430I-2431J-2658D01*
G37*
G36*
G01X989046Y281792D02*
G03Y281201I270J-295D01*
G02X984182I-2432J-2657D01*
G03Y281792I-270J296D01*
G02X984183Y287107I2432J2657D01*
G03Y287697I-270J295D01*
G02X989045I2431J2658D01*
G03Y287107I270J-295D01*
G02X989046Y281792I-2431J-2658D01*
G37*
G36*
G01X976447D02*
G03Y281201I270J-295D01*
G02X971583I-2432J-2657D01*
G03Y281792I-270J296D01*
G02X971584Y287107I2432J2657D01*
G03Y287697I-270J295D01*
G02X976446I2431J2658D01*
G03Y287107I270J-295D01*
G02X976447Y281792I-2431J-2658D01*
G37*
G36*
G01X989045Y259154D02*
G03Y258564I270J-295D01*
G02X984183I-2431J-2658D01*
G03Y259154I-270J295D01*
G02X984182Y264469I2431J2658D01*
G03Y265060I-270J296D01*
G02X989046I2432J2657D01*
G03Y264469I270J-295D01*
G02X989045Y259154I-2432J-2657D01*
G37*
G36*
G01X976446D02*
G03Y258564I270J-295D01*
G02X971584I-2431J-2658D01*
G03Y259154I-270J295D01*
G02X971583Y264469I2431J2658D01*
G03Y265060I-270J296D01*
G02X976447I2432J2657D01*
G03Y264469I270J-295D01*
G02X976446Y259154I-2432J-2657D01*
G37*
G36*
G01X891076Y1208743D02*
G02X886551Y1207906I-2251J-480D01*
G03X886122Y1208243I-395J-62D01*
G02X888204Y1210894I-192J2294D01*
G03X888633Y1210557I395J62D01*
G02X889671Y1210404I192J-2294D01*
G03X890209Y1210860I147J372D01*
G02X890160Y1211256I2251J480D01*
G03X889790Y1211641I-400J-14D01*
G02X887668Y1213785I175J2295D01*
G03X887259Y1214159I-399J-26D01*
G02X884901Y1216352I-59J2301D01*
G03X884527Y1216732I-400J-19D01*
G02X886976Y1219137I150J2297D01*
G03X887350Y1218757I400J19D01*
G02X889497Y1216611I-150J-2297D01*
G03X889906Y1216237I399J26D01*
G02X892265Y1214020I59J-2301D01*
G03X892635Y1213635I400J14D01*
G02X891614Y1209199I-175J-2295D01*
G03X891076Y1208743I-147J-372D01*
G37*
G36*
G01X1014199Y1150681D02*
G02X1011931Y1152301I-2199J-681D01*
G03X1012301Y1152819I-12J400D01*
G02X1016690Y1152791I2199J681D01*
G03X1017134Y1152273I380J-123D01*
G02X1017431Y1152301I364J-2273D01*
G03X1017801Y1152819I-12J400D01*
G02X1020069Y1151199I2199J681D01*
G03X1019699Y1150681I12J-400D01*
G02X1015310Y1150709I-2199J-681D01*
G03X1014866Y1151227I-380J123D01*
G02X1014569Y1151199I-364J2273D01*
G03X1014199Y1150681I12J-400D01*
G37*
G36*
G01X939794Y1106144D02*
G02X937920Y1106110I-893J-2444D01*
G03X937906Y1106856I-151J370D01*
G02X939780Y1106890I893J2444D01*
G03X939794Y1106144I151J-370D01*
G37*
G36*
G01X1002726Y835771D02*
G02X1002715Y838389I-1899J1301D01*
G03X1003373Y838392I328J229D01*
G02X1007058Y838544I1899J-1301D01*
G03X1007750Y838678I310J252D01*
G02X1008164Y836547I2200J-678D01*
G03X1007472Y836413I-310J-252D01*
G02X1003384Y835774I-2200J678D01*
G03X1002726Y835771I-328J-229D01*
G37*
G36*
G01X975032Y827309D02*
G02Y829716I-1962J1204D01*
G03X975714I341J209D01*
G02Y827309I1962J-1203D01*
G03X975032I-341J-209D01*
G37*
G36*
G01X933881Y792485D02*
G02X932275Y793752I-2080J-986D01*
G03X932719Y794315I83J391D01*
G02X934325Y793048I2080J986D01*
G03X933881Y792485I-83J-391D01*
G37*
G36*
G01X987560Y560928D02*
G02X986011Y561941I-1928J-1258D01*
G03X986412Y562554I66J394D01*
G02X987961Y561541I1928J1258D01*
G03X987560Y560928I-66J-394D01*
G37*
G36*
G01X1034958Y372802D02*
G02X1033273Y372022I42J-2302D01*
G03X1032966Y372686I-300J264D01*
G02X1032097Y377136I-42J2302D01*
G03X1032115Y377876I-143J374D01*
G02X1033873Y377833I931J2105D01*
G03X1033855Y377093I143J-374D01*
G02X1034651Y373466I-931J-2105D01*
G03X1034958Y372802I300J-264D01*
G37*
G36*
G01X1128408Y1361725D02*
G03X1127816I-296J-269D01*
G02Y1364821I-1704J1548D01*
G03X1128408I296J269D01*
G02Y1361725I1704J-1548D01*
G37*
G36*
G01X1116408D02*
G03X1115816I-296J-269D01*
G02Y1364821I-1704J1548D01*
G03X1116408I296J269D01*
G02Y1361725I1704J-1548D01*
G37*
G54D25*
X944200Y1083100D03*
X1012000Y371369D03*
X1015537Y365911D03*
G54D24*
X918400Y760750D03*
G54D22*
X165774Y1422700D03*
X145374Y1452500D03*
X145274Y1434685D03*
X167499Y1434000D03*
X114874Y1476700D03*
X118574Y1465900D03*
X137624Y1469000D03*
X175249Y1434075D03*
X135174Y1452400D03*
X139374Y1486100D03*
X446400Y91100D03*
X440849Y111648D03*
X528250Y1470900D03*
X524236Y1463672D03*
X859113Y1283983D03*
X945408Y378761D03*
X950843Y378827D03*
X922525Y519833D03*
X929096Y517567D03*
X944387Y520100D03*
X941557Y547005D03*
X955000Y540800D03*
X938338Y529107D03*
X938579Y551379D03*
X938623Y556600D03*
X956100Y516500D03*
X892400Y633700D03*
X932986Y752682D03*
X942500Y797867D03*
X936543Y762518D03*
X909144Y803346D03*
X903700Y803200D03*
X912762Y792801D03*
X903221Y793938D03*
X931206Y845756D03*
X910807Y766589D03*
X903300Y763200D03*
X889458Y907846D03*
X940750Y886000D03*
X928250Y885250D03*
X934500Y885156D03*
X958256Y894438D03*
X930310Y858550D03*
X895500Y1038000D03*
X944500Y1134500D03*
X952500D03*
X948298Y1215500D03*
X957000Y1207500D03*
X953100Y1211400D03*
X953000Y1203600D03*
X904000Y1191700D03*
X877400D03*
X928500Y1220700D03*
X947700Y1185500D03*
X926700Y1199000D03*
X952500Y1193300D03*
X884056Y1283981D03*
X871556D03*
X1038067Y441886D03*
X1021890Y439717D03*
X965700Y519617D03*
X962118Y534117D03*
X968200Y547200D03*
X984197Y533383D03*
X991538Y522018D03*
X1000051Y547644D03*
X1003591Y552081D03*
X996998Y539555D03*
X990200Y544250D03*
X986638Y519684D03*
X963870Y754152D03*
X964200Y855600D03*
X1009600Y851054D03*
X986471Y829716D03*
X1025636Y854819D03*
X966861Y772518D03*
X1050774Y815327D03*
X1050650Y825420D03*
X1022838Y829101D03*
X1042545Y832026D03*
X1015950Y838000D03*
X1026932Y841614D03*
X1050082Y843729D03*
X993400Y833250D03*
X969926Y847638D03*
X971197Y775799D03*
X1012125Y925875D03*
X1028500Y879500D03*
X997083Y895935D03*
X986728Y891100D03*
X974120Y858920D03*
X1039500Y891100D03*
X1037110Y859471D03*
X989100Y899600D03*
X996938Y901170D03*
X1034200Y945000D03*
X1040200D03*
X1046272Y944928D03*
X1039500Y874700D03*
X1044800Y893750D03*
X1022080Y960728D03*
X1032361Y1114039D03*
X1021970Y1096850D03*
X960500Y1134500D03*
X982500Y1136500D03*
X986500Y1131500D03*
X1013231Y1089300D03*
X1001687Y1111499D03*
X1008739Y1096000D03*
X1029500Y1104900D03*
X1030178Y1134165D03*
X965500Y1128000D03*
X1012800Y1122100D03*
X1002671Y1124700D03*
X977643Y1132490D03*
X1007431Y1122900D03*
X971700Y1193100D03*
X960900Y1211400D03*
Y1203600D03*
X982500Y1144500D03*
X1026100Y1145996D03*
X964550Y1190200D03*
X1056116Y697100D03*
X1057826Y680233D03*
X1059927Y688329D03*
X1064216Y683751D03*
X1067554Y694447D03*
X1071179Y682315D03*
X1075706Y941261D03*
X1058800Y893750D03*
X1124612Y1388773D03*
X1138112Y1363273D03*
X1132112Y1380773D03*
X1126112Y1401773D03*
G54D23*
X961417Y972441D03*
Y703937D03*
%LPD*%
G75*
G54D10*
X100412Y6000D03*
X95412D03*
X90412D03*
X85412D03*
X80412D03*
X75412D03*
X70412D03*
X65412D03*
X60412D03*
X55412D03*
X50412D03*
X45412D03*
X40412D03*
X35412D03*
X30412D03*
X25412D03*
X20412D03*
X15412D03*
X10412D03*
X6000Y6588D03*
Y11588D03*
Y16588D03*
Y21588D03*
Y26588D03*
Y31588D03*
Y36588D03*
Y41588D03*
Y46588D03*
Y51588D03*
Y56588D03*
Y61588D03*
Y66588D03*
Y71588D03*
Y76588D03*
Y81588D03*
Y86588D03*
Y91588D03*
Y96588D03*
Y101588D03*
Y106588D03*
Y111588D03*
Y116588D03*
Y121588D03*
Y126588D03*
Y131588D03*
Y136588D03*
Y141588D03*
Y146588D03*
Y151588D03*
Y156588D03*
Y161588D03*
Y166588D03*
Y171588D03*
Y176588D03*
Y181588D03*
Y186588D03*
Y191588D03*
Y196588D03*
Y201588D03*
Y206588D03*
Y211588D03*
Y216588D03*
Y221588D03*
Y226588D03*
Y231588D03*
Y236588D03*
Y241588D03*
Y246588D03*
Y251588D03*
Y256588D03*
Y261588D03*
Y266588D03*
Y271588D03*
Y276588D03*
Y281588D03*
Y286588D03*
Y291588D03*
Y296588D03*
Y301588D03*
Y306588D03*
Y311588D03*
Y316588D03*
Y321588D03*
Y326588D03*
Y331588D03*
Y336588D03*
Y341588D03*
Y346588D03*
Y351588D03*
Y356588D03*
Y361588D03*
Y366588D03*
Y371588D03*
Y376588D03*
Y441588D03*
Y436588D03*
Y431588D03*
Y426588D03*
Y421588D03*
Y416588D03*
Y411588D03*
Y406588D03*
Y386588D03*
Y391588D03*
Y396588D03*
Y401588D03*
Y446588D03*
Y451588D03*
Y456588D03*
Y461588D03*
Y381588D03*
Y466588D03*
Y471588D03*
Y476588D03*
Y481588D03*
Y486588D03*
Y491588D03*
Y496588D03*
Y501588D03*
Y506588D03*
Y511588D03*
Y516588D03*
Y521588D03*
Y526588D03*
Y531588D03*
Y536588D03*
Y541588D03*
Y546588D03*
Y551588D03*
Y556588D03*
Y561588D03*
Y566588D03*
Y571588D03*
Y576588D03*
Y581588D03*
Y586588D03*
Y591588D03*
Y596588D03*
Y601588D03*
Y606588D03*
Y611588D03*
Y616588D03*
Y621588D03*
Y626588D03*
Y631588D03*
Y636588D03*
Y641588D03*
Y646588D03*
Y651588D03*
Y656588D03*
Y661588D03*
Y666588D03*
Y671588D03*
Y676588D03*
Y681588D03*
Y686588D03*
Y691588D03*
Y696588D03*
Y701588D03*
Y706588D03*
Y711588D03*
Y716588D03*
Y721588D03*
Y726588D03*
Y731588D03*
Y736588D03*
Y741588D03*
Y746588D03*
Y751588D03*
Y756588D03*
Y761588D03*
Y766588D03*
Y771588D03*
Y776588D03*
Y781588D03*
Y786588D03*
Y791588D03*
Y796588D03*
Y801588D03*
Y806588D03*
Y811588D03*
Y816588D03*
Y821588D03*
Y826588D03*
Y831588D03*
Y836588D03*
Y841588D03*
Y846588D03*
Y851588D03*
Y856588D03*
Y861588D03*
Y866588D03*
Y871588D03*
Y876588D03*
Y881588D03*
Y886588D03*
Y891588D03*
Y896588D03*
Y901588D03*
Y906588D03*
Y911588D03*
Y916588D03*
Y921588D03*
Y926588D03*
Y931588D03*
Y936588D03*
Y941588D03*
Y946588D03*
Y951588D03*
Y956588D03*
Y961588D03*
Y966588D03*
Y971588D03*
Y976588D03*
Y981588D03*
Y986588D03*
Y991588D03*
Y996588D03*
Y1001588D03*
Y1006588D03*
Y1011588D03*
Y1016588D03*
Y1021588D03*
Y1026588D03*
Y1031588D03*
Y1036588D03*
Y1041588D03*
Y1046588D03*
Y1051588D03*
Y1056588D03*
Y1061588D03*
Y1066588D03*
Y1071588D03*
Y1076588D03*
Y1081588D03*
Y1086588D03*
Y1091588D03*
Y1096588D03*
Y1101588D03*
Y1106588D03*
Y1111588D03*
Y1116588D03*
Y1121588D03*
Y1126588D03*
Y1131588D03*
Y1136588D03*
Y1141588D03*
Y1146588D03*
Y1151588D03*
Y1156588D03*
Y1161588D03*
Y1166588D03*
Y1171588D03*
Y1176588D03*
Y1181588D03*
Y1186588D03*
Y1191588D03*
Y1196588D03*
Y1201588D03*
Y1206588D03*
Y1211588D03*
Y1216588D03*
Y1221588D03*
Y1226588D03*
Y1231588D03*
Y1236588D03*
Y1321588D03*
Y1326588D03*
Y1331588D03*
Y1286588D03*
Y1291588D03*
Y1296588D03*
Y1301588D03*
Y1306588D03*
Y1311588D03*
Y1316588D03*
Y1241588D03*
Y1246588D03*
Y1251588D03*
Y1256588D03*
Y1261588D03*
Y1266588D03*
Y1271588D03*
Y1276588D03*
Y1281588D03*
Y1421588D03*
Y1416588D03*
Y1411588D03*
Y1406588D03*
Y1401588D03*
Y1396588D03*
Y1391588D03*
Y1386588D03*
Y1381588D03*
Y1376588D03*
Y1371588D03*
Y1366588D03*
Y1361588D03*
Y1356588D03*
Y1351588D03*
Y1346588D03*
Y1341588D03*
Y1426588D03*
Y1336588D03*
Y1451588D03*
Y1446588D03*
Y1441588D03*
Y1436588D03*
Y1431588D03*
X99000Y1501000D03*
X61500Y1502000D03*
X87539Y1499118D03*
X82539D03*
X77539D03*
X72539D03*
X67539D03*
X92539D03*
X11000Y1455500D03*
X15500Y1458500D03*
X17811Y1462693D03*
Y1467693D03*
Y1472693D03*
Y1477693D03*
Y1482693D03*
Y1487693D03*
Y1492693D03*
Y1497693D03*
Y1502693D03*
Y1507693D03*
X17500Y1512000D03*
X21819Y1513685D03*
X26819D03*
X31819D03*
X36819D03*
X41819D03*
X46819D03*
X51819D03*
X56819D03*
X58500Y1508000D03*
X195412Y6000D03*
X190412D03*
X185412D03*
X180412D03*
X175412D03*
X170412D03*
X165412D03*
X160412D03*
X155412D03*
X150412D03*
X145412D03*
X140412D03*
X135412D03*
X130412D03*
X125412D03*
X120412D03*
X115412D03*
X110412D03*
X105412D03*
X180000Y1424000D03*
Y1430000D03*
X186000Y1424000D03*
Y1430000D03*
X102000Y1505500D03*
X177433Y1513685D03*
X182433D03*
X187433D03*
X192433D03*
X147433D03*
X152433D03*
X157433D03*
X162433D03*
X167433D03*
X172433D03*
X103000Y1511000D03*
X107433Y1513685D03*
X112433D03*
X117433D03*
X122433D03*
X127433D03*
X132433D03*
X137433D03*
X142433D03*
X290412Y6000D03*
X285412D03*
X280412D03*
X275412D03*
X270412D03*
X265412D03*
X260412D03*
X255412D03*
X250412D03*
X245412D03*
X240412D03*
X235412D03*
X230412D03*
X225412D03*
X220412D03*
X215412D03*
X210412D03*
X205412D03*
X200412D03*
X283000Y1492000D03*
X279000Y1498500D03*
X197433Y1513685D03*
X202433D03*
X207433D03*
X212433D03*
X217433D03*
X222433D03*
X227433D03*
X232433D03*
X237433D03*
X242433D03*
X247433D03*
X252433D03*
X257433D03*
X262433D03*
X267433D03*
X272433D03*
X277433D03*
X278646Y1509398D03*
Y1504398D03*
X288685Y1490063D03*
X385412Y6000D03*
X380412D03*
X375412D03*
X370412D03*
X365412D03*
X360412D03*
X355412D03*
X350412D03*
X345412D03*
X340412D03*
X335412D03*
X330412D03*
X325412D03*
X320412D03*
X315412D03*
X310412D03*
X305412D03*
X300412D03*
X295412D03*
X293685Y1490063D03*
X298685D03*
X303685D03*
X308685D03*
X313685D03*
X318685D03*
X323685D03*
X328685D03*
X333685D03*
X338685D03*
X343685D03*
X348685D03*
X353685D03*
X358685D03*
X363685D03*
X368685D03*
X373685D03*
X378685D03*
X383685D03*
X480412Y6000D03*
X475412D03*
X470412D03*
X465412D03*
X460412D03*
X455412D03*
X450412D03*
X445412D03*
X440412D03*
X435412D03*
X430412D03*
X425412D03*
X420412D03*
X415412D03*
X410412D03*
X405412D03*
X400412D03*
X395412D03*
X390412D03*
X388685Y1490063D03*
X393685D03*
X398685D03*
X403685D03*
X408685D03*
X413685D03*
X418685D03*
X423685D03*
X428685D03*
X433685D03*
X438685D03*
X443685D03*
X448685D03*
X453685D03*
X458685D03*
X463685D03*
X468685D03*
X473685D03*
X478685D03*
X575412Y6000D03*
X570412D03*
X565412D03*
X560412D03*
X555412D03*
X550412D03*
X545412D03*
X540412D03*
X535412D03*
X530412D03*
X525412D03*
X520412D03*
X515412D03*
X510412D03*
X505412D03*
X500412D03*
X495412D03*
X490412D03*
X485412D03*
X501000Y1494000D03*
X503000Y1499000D03*
X494500Y1490500D03*
X574937Y1513685D03*
X569937D03*
X564937D03*
X559937D03*
X554937D03*
X549937D03*
X544937D03*
X539937D03*
X534937D03*
X529937D03*
X524937D03*
X483685Y1490063D03*
X488685D03*
X503244Y1504378D03*
Y1509378D03*
X504937Y1513685D03*
X509937D03*
X514937D03*
X519937D03*
X513917Y1447297D03*
X507917D03*
X519717D03*
X670412Y6000D03*
X665412D03*
X660412D03*
X655412D03*
X650412D03*
X645412D03*
X640412D03*
X635412D03*
X630412D03*
X625412D03*
X620412D03*
X615412D03*
X610412D03*
X605412D03*
X600412D03*
X595412D03*
X590412D03*
X585412D03*
X580412D03*
X669937Y1513685D03*
X659937D03*
X654937D03*
X649937D03*
X644937D03*
X639937D03*
X634937D03*
X629937D03*
X624937D03*
X619937D03*
X614937D03*
X609937D03*
X604937D03*
X599937D03*
X594937D03*
X589937D03*
X584937D03*
X579937D03*
X664937D03*
X765412Y6000D03*
X760412D03*
X755412D03*
X750412D03*
X745412D03*
X740412D03*
X735412D03*
X730412D03*
X725412D03*
X720412D03*
X715412D03*
X710412D03*
X705412D03*
X700412D03*
X695412D03*
X690412D03*
X685412D03*
X680412D03*
X675412D03*
X722000Y1503500D03*
X718500Y1500000D03*
X680500Y1503500D03*
X674937Y1513685D03*
X688012Y1499118D03*
X693012D03*
X698012D03*
X703012D03*
X708012D03*
X713012D03*
X724000Y1509500D03*
X725551Y1513685D03*
X730551D03*
X735551D03*
X740551D03*
X745551D03*
X750551D03*
X755551D03*
X760551D03*
X765551D03*
X678500Y1510500D03*
X777465Y93947D03*
Y88947D03*
Y83947D03*
Y78947D03*
Y73947D03*
Y68947D03*
Y63947D03*
Y58947D03*
Y53947D03*
Y48947D03*
Y43947D03*
Y38947D03*
Y33947D03*
Y28947D03*
Y23947D03*
Y18947D03*
Y13947D03*
X778000Y9500D03*
X775412Y6000D03*
X770412D03*
X777465Y183947D03*
Y178947D03*
Y173947D03*
Y168947D03*
Y163947D03*
Y158947D03*
Y153947D03*
Y148947D03*
Y143947D03*
Y138947D03*
Y133947D03*
Y128947D03*
Y123947D03*
Y118947D03*
Y113947D03*
Y108947D03*
Y103947D03*
Y98947D03*
X809500Y197500D03*
X805522Y195764D03*
X808961Y201678D03*
Y206678D03*
Y211678D03*
Y216678D03*
Y236678D03*
Y231678D03*
Y226678D03*
Y221678D03*
Y241678D03*
X779022Y190764D03*
X784022Y194764D03*
X800522Y195764D03*
X795522D03*
X790522D03*
X779500Y1491000D03*
X775000Y1495500D03*
X770551Y1513685D03*
X773528Y1510662D03*
Y1505662D03*
Y1500662D03*
X786803Y1490063D03*
X791803D03*
X796803D03*
X801803D03*
X806803D03*
X811803D03*
X816803D03*
X821803D03*
X826803D03*
X831803D03*
X836803D03*
X841803D03*
X846803D03*
X851803D03*
X856803D03*
X861803D03*
X887127Y254031D03*
X866803Y1490063D03*
X871803D03*
X876803D03*
X881803D03*
X886803D03*
X891803D03*
X896803D03*
X901803D03*
X906803D03*
X911803D03*
X916803D03*
X921803D03*
X926803D03*
X931803D03*
X936803D03*
X941803D03*
X946803D03*
X951803D03*
X956803D03*
X997000Y1496000D03*
X993000Y1491500D03*
X961803Y1490063D03*
X966803D03*
X971803D03*
X976803D03*
X981803D03*
X986803D03*
X998126Y1503614D03*
Y1508614D03*
Y1513614D03*
X1003126D03*
X1008126D03*
X1013126D03*
X1018126D03*
X1023126D03*
X1028126D03*
X1033126D03*
X1038126D03*
X1043126D03*
X1048126D03*
X1053126D03*
X1068734Y195764D03*
X1064500Y197500D03*
X1065055Y201895D03*
Y206895D03*
Y211895D03*
Y216895D03*
Y226895D03*
Y231895D03*
Y236895D03*
Y241895D03*
Y221895D03*
X1148734Y195764D03*
X1143734D03*
X1138734D03*
X1133734D03*
X1128734D03*
X1123734D03*
X1118734D03*
X1113734D03*
X1103734D03*
X1098734D03*
X1093734D03*
X1088734D03*
X1083734D03*
X1078734D03*
X1073734D03*
X1075627Y374973D03*
X1075829Y380885D03*
X1076142Y386839D03*
X1087933Y1411323D03*
X1082933D03*
X1077933D03*
X1095567Y1426057D03*
X1058126Y1513614D03*
X1061675Y1510352D03*
X1065210Y1506817D03*
X1066638Y1472408D03*
Y1467408D03*
Y1462408D03*
Y1457408D03*
Y1452408D03*
Y1447408D03*
Y1442408D03*
X1095567Y1431057D03*
Y1436057D03*
Y1441057D03*
Y1446057D03*
Y1451057D03*
Y1456057D03*
Y1461057D03*
Y1466057D03*
X1096039Y1505861D03*
X1099575Y1509397D03*
X1103110Y1512932D03*
X1107798Y1513685D03*
X1112798D03*
X1117798D03*
X1122798D03*
X1127798D03*
X1132798D03*
X1137798D03*
X1142798D03*
X1147798D03*
X1095567Y1471057D03*
X1066638Y1502408D03*
X1234500Y6000D03*
X1243844D03*
X1238844D03*
X1230409Y7565D03*
Y12565D03*
Y17565D03*
Y22565D03*
Y27565D03*
Y32565D03*
Y37565D03*
Y42565D03*
Y47565D03*
Y52565D03*
Y57565D03*
Y62565D03*
Y67565D03*
Y72565D03*
Y77565D03*
Y82565D03*
Y87565D03*
Y92565D03*
X1229000Y189500D03*
X1230409Y97565D03*
Y102565D03*
Y107565D03*
Y112565D03*
Y117565D03*
Y122565D03*
Y127565D03*
Y132565D03*
Y137565D03*
Y142565D03*
Y147565D03*
Y152565D03*
Y157565D03*
Y162565D03*
Y167565D03*
Y172565D03*
Y177565D03*
Y182565D03*
X1225000Y194000D03*
X1218734Y195764D03*
X1213734D03*
X1208734D03*
X1203734D03*
X1198734D03*
X1193734D03*
X1188734D03*
X1183734D03*
X1178734D03*
X1173734D03*
X1168734D03*
X1163734D03*
X1158734D03*
X1153734D03*
X1151100Y1179300D03*
X1155900D03*
X1151100Y1184100D03*
X1155900D03*
Y1188900D03*
X1151100D03*
X1245500Y1500500D03*
X1208000Y1502500D03*
X1234783Y1499118D03*
X1229783D03*
X1224783D03*
X1219783D03*
X1214783D03*
X1239783D03*
X1152798Y1513685D03*
X1157798D03*
X1162798D03*
X1167798D03*
X1172798D03*
X1177798D03*
X1182798D03*
X1187798D03*
X1192798D03*
X1197798D03*
X1202798D03*
X1205500Y1509000D03*
X1338844Y6000D03*
X1333844D03*
X1328844D03*
X1323844D03*
X1318844D03*
X1313844D03*
X1308844D03*
X1303844D03*
X1298844D03*
X1293844D03*
X1288844D03*
X1283844D03*
X1278844D03*
X1273844D03*
X1268844D03*
X1263844D03*
X1258844D03*
X1253844D03*
X1248844D03*
X1249000Y1504500D03*
X1328464Y1513685D03*
X1333464D03*
X1338464D03*
X1293464D03*
X1298464D03*
X1303464D03*
X1308464D03*
X1313464D03*
X1318464D03*
X1323464D03*
X1250500Y1510500D03*
X1253464Y1513685D03*
X1258464D03*
X1263464D03*
X1268464D03*
X1273464D03*
X1278464D03*
X1283464D03*
X1288464D03*
X1433844Y6000D03*
X1428844D03*
X1423844D03*
X1418844D03*
X1413844D03*
X1408844D03*
X1403844D03*
X1398844D03*
X1393844D03*
X1388844D03*
X1383844D03*
X1378844D03*
X1373844D03*
X1368844D03*
X1363844D03*
X1358844D03*
X1353844D03*
X1348844D03*
X1343844D03*
X1433500Y1490500D03*
X1428500Y1494000D03*
X1403500Y1513500D03*
X1398500D03*
X1363464Y1513685D03*
X1368464D03*
X1373464D03*
X1378464D03*
X1383464D03*
X1388464D03*
X1393464D03*
X1353464D03*
X1358464D03*
X1343464D03*
X1348464D03*
X1408464D03*
X1413464D03*
X1418464D03*
X1423464D03*
X1425890Y1510111D03*
Y1505111D03*
Y1500111D03*
X1528844Y6000D03*
X1523844D03*
X1518844D03*
X1513844D03*
X1508844D03*
X1503844D03*
X1498844D03*
X1493844D03*
X1488844D03*
X1483844D03*
X1478844D03*
X1473844D03*
X1468844D03*
X1463844D03*
X1458844D03*
X1453844D03*
X1448844D03*
X1443844D03*
X1438844D03*
X1439716Y1490063D03*
X1444716D03*
X1449716D03*
X1454716D03*
X1459716D03*
X1464716D03*
X1469716D03*
X1474716D03*
X1479716D03*
X1484716D03*
X1489716D03*
X1494716D03*
X1499716D03*
X1504716D03*
X1509716D03*
X1514716D03*
X1519716D03*
X1524716D03*
X1529716D03*
X1623844Y6000D03*
X1618844D03*
X1613844D03*
X1608844D03*
X1603844D03*
X1598844D03*
X1593844D03*
X1588844D03*
X1583844D03*
X1578844D03*
X1573844D03*
X1568844D03*
X1563844D03*
X1558844D03*
X1553844D03*
X1548844D03*
X1543844D03*
X1538844D03*
X1533844D03*
X1534716Y1490063D03*
X1539716D03*
X1544716D03*
X1549716D03*
X1554716D03*
X1559716D03*
X1564716D03*
X1569716D03*
X1574716D03*
X1579716D03*
X1584716D03*
X1589716D03*
X1594716D03*
X1599716D03*
X1604716D03*
X1609716D03*
X1614716D03*
X1619716D03*
X1624716D03*
X1718844Y6000D03*
X1713844D03*
X1708844D03*
X1703844D03*
X1698844D03*
X1693844D03*
X1688844D03*
X1683844D03*
X1678844D03*
X1673844D03*
X1668844D03*
X1663844D03*
X1658844D03*
X1653844D03*
X1648844D03*
X1643844D03*
X1638844D03*
X1633844D03*
X1628844D03*
X1649500Y1497500D03*
X1646000Y1492000D03*
X1720968Y1513685D03*
X1715968D03*
X1710968D03*
X1705968D03*
X1700968D03*
X1695968D03*
X1690968D03*
X1685968D03*
X1680968D03*
X1670968D03*
X1675968D03*
X1629716Y1490063D03*
X1634716D03*
X1639716D03*
X1650488Y1504165D03*
Y1509165D03*
X1650968Y1513685D03*
X1655968D03*
X1660968D03*
X1665968D03*
X1813844Y6000D03*
X1808844D03*
X1803844D03*
X1798844D03*
X1793844D03*
X1788844D03*
X1783844D03*
X1778844D03*
X1773844D03*
X1768844D03*
X1763844D03*
X1758844D03*
X1753844D03*
X1748844D03*
X1743844D03*
X1738844D03*
X1733844D03*
X1728844D03*
X1723844D03*
X1786004Y1513500D03*
X1780968Y1513685D03*
X1775968D03*
X1770968D03*
X1765968D03*
X1760968D03*
X1755968D03*
X1750968D03*
X1745968D03*
X1740968D03*
X1796004Y1513500D03*
X1801004D03*
X1806004D03*
X1811004D03*
X1816004D03*
X1730968Y1513685D03*
X1725968D03*
X1791004Y1513500D03*
X1735968Y1513685D03*
X1913844Y6000D03*
X1908844D03*
X1903844D03*
X1898844D03*
X1893844D03*
X1888844D03*
X1883844D03*
X1878844D03*
X1873844D03*
X1868844D03*
X1863844D03*
X1858844D03*
X1853844D03*
X1848844D03*
X1843844D03*
X1838844D03*
X1833844D03*
X1828844D03*
X1823844D03*
X1818844D03*
X1869500Y1503500D03*
X1865500Y1500000D03*
X1829500Y1501500D03*
X1826500Y1506500D03*
X1855256Y1499118D03*
X1850256D03*
X1845256D03*
X1840256D03*
X1826040Y1513315D03*
X1821040D03*
X1835256Y1499118D03*
X1860256D03*
X1871157Y1509110D03*
X1871582Y1513685D03*
X1876582D03*
X1881582D03*
X1886582D03*
X1891582D03*
X1896582D03*
X1901582D03*
X1906582D03*
X1911582D03*
X1928843Y8985D03*
Y93985D03*
Y88985D03*
Y83985D03*
Y78985D03*
Y73985D03*
Y68985D03*
Y63985D03*
Y58985D03*
Y53985D03*
Y48985D03*
Y43985D03*
Y38985D03*
Y28985D03*
Y23985D03*
Y18985D03*
Y13985D03*
Y33985D03*
X1923844Y6000D03*
X1918844D03*
X1928843Y98985D03*
Y188985D03*
Y183985D03*
Y178985D03*
Y173985D03*
Y168985D03*
Y163985D03*
Y158985D03*
Y153985D03*
Y148985D03*
Y143985D03*
Y138985D03*
Y133985D03*
Y128985D03*
Y123985D03*
Y118985D03*
Y113985D03*
Y108985D03*
Y103985D03*
Y283985D03*
Y278985D03*
Y273985D03*
Y268985D03*
Y263985D03*
Y258985D03*
Y253985D03*
Y248985D03*
Y243985D03*
Y238985D03*
Y233985D03*
Y228985D03*
Y223985D03*
Y218985D03*
Y213985D03*
Y208985D03*
Y203985D03*
Y198985D03*
Y193985D03*
Y378985D03*
Y373985D03*
Y368985D03*
Y363985D03*
Y358985D03*
Y353985D03*
Y348985D03*
Y343985D03*
Y338985D03*
Y333985D03*
Y328985D03*
Y323985D03*
Y318985D03*
Y313985D03*
Y308985D03*
Y303985D03*
Y298985D03*
Y293985D03*
Y288985D03*
Y418985D03*
Y433985D03*
Y428985D03*
Y423985D03*
Y473985D03*
Y468985D03*
Y463985D03*
Y458985D03*
Y453985D03*
Y448985D03*
Y443985D03*
Y438985D03*
Y413985D03*
Y408985D03*
Y403985D03*
Y398985D03*
Y393985D03*
Y388985D03*
Y383985D03*
Y568985D03*
Y563985D03*
Y558985D03*
Y553985D03*
Y548985D03*
Y543985D03*
Y538985D03*
Y533985D03*
Y528985D03*
Y523985D03*
Y518985D03*
Y513985D03*
Y508985D03*
Y503985D03*
Y498985D03*
Y493985D03*
Y488985D03*
Y483985D03*
Y478985D03*
Y663985D03*
Y658985D03*
Y653985D03*
Y648985D03*
Y643985D03*
Y638985D03*
Y633985D03*
Y628985D03*
Y623985D03*
Y618985D03*
Y613985D03*
Y608985D03*
Y603985D03*
Y598985D03*
Y593985D03*
Y588985D03*
Y583985D03*
Y578985D03*
Y573985D03*
Y758985D03*
Y753985D03*
Y748985D03*
Y743985D03*
Y738985D03*
Y733985D03*
Y728985D03*
Y723985D03*
Y718985D03*
Y713985D03*
Y708985D03*
Y703985D03*
Y698985D03*
Y693985D03*
Y688985D03*
Y683985D03*
Y678985D03*
Y673985D03*
Y668985D03*
Y853985D03*
Y848985D03*
Y843985D03*
Y838985D03*
Y833985D03*
Y828985D03*
Y823985D03*
Y818985D03*
Y813985D03*
Y808985D03*
Y803985D03*
Y798985D03*
Y793985D03*
Y788985D03*
Y783985D03*
Y778985D03*
Y773985D03*
Y768985D03*
Y763985D03*
Y918985D03*
Y913985D03*
Y908985D03*
Y903985D03*
Y898985D03*
Y893985D03*
Y888985D03*
Y883985D03*
Y878985D03*
Y873985D03*
Y868985D03*
Y863985D03*
Y858985D03*
Y948985D03*
Y943985D03*
Y938985D03*
Y933985D03*
Y928985D03*
Y923985D03*
Y1043985D03*
Y1038985D03*
Y1033985D03*
Y1028985D03*
Y1023985D03*
Y1018985D03*
Y1013985D03*
Y1008985D03*
Y1003985D03*
Y998985D03*
Y993985D03*
Y988985D03*
Y983985D03*
Y978985D03*
Y973985D03*
Y968985D03*
Y963985D03*
Y958985D03*
Y953985D03*
Y1143985D03*
Y1138985D03*
Y1133985D03*
Y1128985D03*
Y1123985D03*
Y1118985D03*
Y1113985D03*
Y1108985D03*
Y1103985D03*
Y1098985D03*
Y1093985D03*
Y1088985D03*
Y1083985D03*
Y1078985D03*
Y1073985D03*
Y1068985D03*
Y1063985D03*
Y1058985D03*
Y1053985D03*
Y1048985D03*
Y1238985D03*
Y1233985D03*
Y1228985D03*
Y1223985D03*
Y1218985D03*
Y1213985D03*
Y1208985D03*
Y1203985D03*
Y1198985D03*
Y1193985D03*
Y1188985D03*
Y1183985D03*
Y1178985D03*
Y1173985D03*
Y1168985D03*
Y1163985D03*
Y1158985D03*
Y1153985D03*
Y1148985D03*
Y1288985D03*
Y1293985D03*
Y1298985D03*
Y1303985D03*
Y1308985D03*
Y1313985D03*
Y1318985D03*
Y1323985D03*
Y1328985D03*
Y1333985D03*
Y1283985D03*
Y1278985D03*
Y1273985D03*
Y1268985D03*
Y1263985D03*
Y1258985D03*
Y1253985D03*
Y1248985D03*
Y1243985D03*
Y1348985D03*
Y1353985D03*
Y1358985D03*
Y1363985D03*
Y1368985D03*
Y1373985D03*
Y1378985D03*
Y1383985D03*
Y1388985D03*
Y1393985D03*
Y1398985D03*
Y1403985D03*
Y1408985D03*
Y1413985D03*
Y1418985D03*
Y1423985D03*
Y1428985D03*
Y1338985D03*
Y1343985D03*
Y1448985D03*
Y1443985D03*
Y1433985D03*
Y1438985D03*
X1920000Y1458000D03*
X1917500Y1463500D03*
X1916582Y1513685D03*
X1917031Y1509134D03*
Y1504134D03*
Y1499134D03*
Y1494134D03*
Y1489134D03*
Y1484134D03*
Y1479134D03*
Y1474134D03*
Y1469134D03*
X1926500Y1455000D03*
G54D20*
G01X489037Y-206331D02*
X489911Y-205456D01*
X490566Y-203998D01*
X491003Y-201955D01*
X490566Y-200206D01*
X489693Y-199039D01*
X488164Y-198164D01*
X482269D01*
Y-215664D01*
X489474D01*
X491003Y-214498D01*
X491876Y-212747D01*
X492313Y-210706D01*
X491876Y-208664D01*
X490566Y-206914D01*
X489037Y-206331D01*
X482269D01*
G01X501734Y-215664D02*
Y-203998D01*
G01Y-206331D02*
X502826Y-205164D01*
X503918Y-204289D01*
X505446Y-203998D01*
X506537Y-204289D01*
X507848Y-205164D01*
G01X517706Y-220914D02*
X519016Y-221497D01*
X520763Y-220914D01*
X521854Y-219748D01*
X522728Y-218289D01*
X524037Y-213623D01*
X526876Y-203998D01*
G01X519889D02*
X524037Y-213623D01*
G01X543284Y-205456D02*
X541756Y-204289D01*
X540446Y-203998D01*
X538699Y-204581D01*
X537389Y-205747D01*
X536516Y-207789D01*
X536297Y-209831D01*
X536516Y-211873D01*
X537389Y-213623D01*
X538699Y-215081D01*
X540446Y-215664D01*
X541974Y-215081D01*
X543284Y-213914D01*
G01X554016Y-207789D02*
X561003D01*
X560348Y-205747D01*
X559256Y-204581D01*
X557728Y-203998D01*
X556199Y-204289D01*
X554889Y-205164D01*
X554016Y-207206D01*
X553579Y-208956D01*
Y-210706D01*
X554016Y-212456D01*
X555108Y-214206D01*
X556418Y-215372D01*
X557946Y-215664D01*
X559474Y-215081D01*
X561003Y-213331D01*
G01X597094Y-199623D02*
X595784Y-198747D01*
X594256Y-198164D01*
X592509D01*
X590544Y-199039D01*
X589016Y-200497D01*
X587924Y-202248D01*
X587051Y-205164D01*
X586832Y-207789D01*
X587269Y-210414D01*
X587924Y-212164D01*
X589234Y-213914D01*
X590763Y-215081D01*
X592291Y-215664D01*
X593819D01*
X595348Y-215081D01*
X596658Y-214206D01*
X597750Y-213040D01*
G01X613721Y-215664D02*
Y-203998D01*
G01Y-206039D02*
X612848Y-204873D01*
X611537Y-204289D01*
X610009Y-203998D01*
X608481Y-204581D01*
X607171Y-205747D01*
X606297Y-207497D01*
X605861Y-209831D01*
X606297Y-212164D01*
X607171Y-213914D01*
X608481Y-215081D01*
X610009Y-215664D01*
X611537Y-215372D01*
X612848Y-214498D01*
X613721Y-213331D01*
G01X623579Y-215664D02*
Y-203998D01*
G01Y-206914D02*
X624453Y-205456D01*
X625763Y-204289D01*
X627509Y-203998D01*
X629037Y-204289D01*
X630348Y-205456D01*
X631003Y-207497D01*
Y-215664D01*
G01X640206Y-220914D02*
X641516Y-221497D01*
X643263Y-220914D01*
X644354Y-219748D01*
X645228Y-218289D01*
X646537Y-213623D01*
X649376Y-203998D01*
G01X642389D02*
X646537Y-213623D01*
G01X662291Y-215664D02*
X660981Y-215372D01*
X659671Y-214206D01*
X658797Y-212164D01*
X658361Y-209831D01*
X658797Y-207497D01*
X659671Y-205456D01*
X660981Y-204289D01*
X662291Y-203998D01*
X663601Y-204289D01*
X664911Y-205456D01*
X665784Y-207497D01*
X666003Y-209831D01*
X665784Y-212164D01*
X664911Y-214206D01*
X663601Y-215372D01*
X662291Y-215664D01*
G01X676079D02*
Y-203998D01*
G01Y-206914D02*
X676953Y-205456D01*
X678263Y-204289D01*
X680009Y-203998D01*
X681537Y-204289D01*
X682848Y-205456D01*
X683503Y-207497D01*
Y-215664D01*
G01X710424D02*
Y-198164D01*
X715883D01*
X717629Y-199039D01*
X718721Y-200206D01*
X719158Y-202539D01*
X718721Y-204873D01*
X717411Y-206331D01*
X715883Y-207206D01*
X710424D01*
G01X715883D02*
X719158Y-215664D01*
G01X732291Y-216247D02*
X731854Y-215956D01*
Y-215372D01*
X732291Y-215081D01*
X732728Y-215372D01*
Y-215956D01*
X732291Y-216247D01*
G01X744988Y-215664D02*
Y-198164D01*
X749354D01*
X751101Y-199039D01*
X752411Y-200206D01*
X753503Y-201955D01*
X754376Y-203998D01*
X754594Y-206914D01*
X754376Y-209831D01*
X753503Y-211873D01*
X752411Y-213623D01*
X751101Y-214789D01*
X749354Y-215664D01*
X744988D01*
G01X762924D02*
Y-198164D01*
X768164D01*
X769911Y-199039D01*
X771221Y-201081D01*
X771658Y-203414D01*
X771221Y-205747D01*
X770129Y-207497D01*
X768164Y-208373D01*
X762924D01*
G01X786537Y-206331D02*
X787411Y-205456D01*
X788066Y-203998D01*
X788503Y-201955D01*
X788066Y-200206D01*
X787193Y-199039D01*
X785664Y-198164D01*
X779769D01*
Y-215664D01*
X786974D01*
X788503Y-214498D01*
X789376Y-212747D01*
X789813Y-210706D01*
X789376Y-208664D01*
X788066Y-206914D01*
X786537Y-206331D01*
X779769D01*
G01X595364Y-170664D02*
Y-153164D01*
X601041Y-167747D01*
X606718Y-153164D01*
Y-170664D01*
G01X618541D02*
X617231Y-170372D01*
X615921Y-169206D01*
X615047Y-167164D01*
X614611Y-164831D01*
X615047Y-162497D01*
X615921Y-160456D01*
X617231Y-159289D01*
X618541Y-158998D01*
X619851Y-159289D01*
X621161Y-160456D01*
X622034Y-162497D01*
X622253Y-164831D01*
X622034Y-167164D01*
X621161Y-169206D01*
X619851Y-170372D01*
X618541Y-170664D01*
G01X639971Y-153164D02*
Y-170664D01*
G01Y-168040D02*
X639098Y-169498D01*
X637787Y-170372D01*
X636259Y-170664D01*
X634513Y-170081D01*
X633203Y-168623D01*
X632329Y-166873D01*
X632111Y-164831D01*
X632329Y-162789D01*
X633203Y-161039D01*
X634513Y-159581D01*
X636259Y-158998D01*
X637787Y-159289D01*
X638879Y-159873D01*
X639971Y-161039D01*
G01X650266Y-162789D02*
X657253D01*
X656598Y-160747D01*
X655506Y-159581D01*
X653978Y-158998D01*
X652449Y-159289D01*
X651139Y-160164D01*
X650266Y-162206D01*
X649829Y-163956D01*
Y-165706D01*
X650266Y-167456D01*
X651358Y-169206D01*
X652668Y-170372D01*
X654196Y-170664D01*
X655724Y-170081D01*
X657253Y-168331D01*
G01X671041Y-170664D02*
Y-153164D01*
G01X839441Y-215664D02*
Y-198164D01*
X836821Y-201664D01*
G01Y-215664D02*
X842061D01*
G01X852793Y-208373D02*
X854321Y-206331D01*
X855631Y-205164D01*
X857378Y-204581D01*
X858906Y-205164D01*
X859998Y-206331D01*
X860871Y-208081D01*
X861089Y-210122D01*
X860871Y-211873D01*
X859998Y-213623D01*
X858687Y-215081D01*
X857159Y-215664D01*
X855413Y-215081D01*
X853884Y-213331D01*
X853011Y-210706D01*
X852793Y-207789D01*
X853229Y-203998D01*
X853884Y-201955D01*
X854976Y-199914D01*
X856504Y-198456D01*
X858033Y-198164D01*
X859561Y-198747D01*
X860653Y-200206D01*
G01X869638Y-212164D02*
X870947Y-214206D01*
X872694Y-215372D01*
X874659Y-215664D01*
X876406Y-215372D01*
X878153Y-213914D01*
X879244Y-212164D01*
X879463Y-210414D01*
X879026Y-208373D01*
X877498Y-206914D01*
X875969Y-206331D01*
X874004D01*
G01X875969D02*
X877279Y-205456D01*
X878371Y-203998D01*
X878808Y-202248D01*
X878371Y-200497D01*
X877279Y-199039D01*
X875314Y-198164D01*
X873349Y-198456D01*
X871384Y-199623D01*
G01X891941Y-215664D02*
Y-198164D01*
X889321Y-201664D01*
G01Y-215664D02*
X894561D01*
G01X909004D02*
X909441Y-211873D01*
X910096Y-208664D01*
X910969Y-205747D01*
X912061Y-202539D01*
X913808Y-198164D01*
X905074D01*
G01X826324Y-170664D02*
Y-153164D01*
X831564D01*
X833311Y-154039D01*
X834621Y-156081D01*
X835058Y-158414D01*
X834621Y-160747D01*
X833529Y-162497D01*
X831564Y-163373D01*
X826324D01*
G01X852994Y-154623D02*
X851684Y-153747D01*
X850156Y-153164D01*
X848409D01*
X846444Y-154039D01*
X844916Y-155497D01*
X843824Y-157248D01*
X842951Y-160164D01*
X842732Y-162789D01*
X843169Y-165414D01*
X843824Y-167164D01*
X845134Y-168914D01*
X846663Y-170081D01*
X848191Y-170664D01*
X849719D01*
X851248Y-170081D01*
X852558Y-169206D01*
X853650Y-168040D01*
G01X867437Y-161331D02*
X868311Y-160456D01*
X868966Y-158998D01*
X869403Y-156955D01*
X868966Y-155206D01*
X868093Y-154039D01*
X866564Y-153164D01*
X860669D01*
Y-170664D01*
X867874D01*
X869403Y-169498D01*
X870276Y-167747D01*
X870713Y-165706D01*
X870276Y-163664D01*
X868966Y-161914D01*
X867437Y-161331D01*
X860669D01*
G01X876641Y-176497D02*
X889741D01*
G01X895669Y-170664D02*
Y-153164D01*
X905713Y-170664D01*
Y-153164D01*
G01X918191Y-170664D02*
X916444Y-170372D01*
X914916Y-169206D01*
X913606Y-167456D01*
X912732Y-165414D01*
X912296Y-163081D01*
Y-160747D01*
X912732Y-158414D01*
X913606Y-156372D01*
X914916Y-154623D01*
X916444Y-153456D01*
X918191Y-153164D01*
X919937Y-153456D01*
X921466Y-154623D01*
X922776Y-156372D01*
X923650Y-158414D01*
X924086Y-160747D01*
Y-163081D01*
X923650Y-165414D01*
X922776Y-167456D01*
X921466Y-169206D01*
X919937Y-170372D01*
X918191Y-170664D01*
G01X1000741Y-215664D02*
Y-198164D01*
X998121Y-201664D01*
G01Y-215664D02*
X1003361D01*
G01X969032Y-153164D02*
X974491Y-170664D01*
X979950Y-153164D01*
G01X996358Y-170664D02*
X987624D01*
Y-153164D01*
X996358D01*
G01X992864Y-161622D02*
X987624D01*
G01X1005124Y-170664D02*
Y-153164D01*
X1010583D01*
X1012329Y-154039D01*
X1013421Y-155206D01*
X1013858Y-157539D01*
X1013421Y-159873D01*
X1012111Y-161331D01*
X1010583Y-162206D01*
X1005124D01*
G01X1010583D02*
X1013858Y-170664D01*
G01X1026991Y-171247D02*
X1026554Y-170956D01*
Y-170372D01*
X1026991Y-170081D01*
X1027428Y-170372D01*
Y-170956D01*
X1026991Y-171247D01*
G01X1128824Y-198164D02*
Y-215664D01*
X1137558D01*
G01X1145888Y-212164D02*
X1147197Y-214206D01*
X1148944Y-215372D01*
X1150909Y-215664D01*
X1152656Y-215372D01*
X1154403Y-213914D01*
X1155494Y-212164D01*
X1155713Y-210414D01*
X1155276Y-208373D01*
X1153748Y-206914D01*
X1152219Y-206331D01*
X1150254D01*
G01X1152219D02*
X1153529Y-205456D01*
X1154621Y-203998D01*
X1155058Y-202248D01*
X1154621Y-200497D01*
X1153529Y-199039D01*
X1151564Y-198164D01*
X1149599Y-198456D01*
X1147634Y-199623D01*
G01X1102574Y-153164D02*
Y-170664D01*
X1111308D01*
G01X1128371D02*
Y-158998D01*
G01Y-161039D02*
X1127498Y-159873D01*
X1126187Y-159289D01*
X1124659Y-158998D01*
X1123131Y-159581D01*
X1121821Y-160747D01*
X1120947Y-162497D01*
X1120511Y-164831D01*
X1120947Y-167164D01*
X1121821Y-168914D01*
X1123131Y-170081D01*
X1124659Y-170664D01*
X1126187Y-170372D01*
X1127498Y-169498D01*
X1128371Y-168331D01*
G01X1137356Y-175914D02*
X1138666Y-176497D01*
X1140413Y-175914D01*
X1141504Y-174748D01*
X1142378Y-173289D01*
X1143687Y-168623D01*
X1146526Y-158998D01*
G01X1139539D02*
X1143687Y-168623D01*
G01X1156166Y-162789D02*
X1163153D01*
X1162498Y-160747D01*
X1161406Y-159581D01*
X1159878Y-158998D01*
X1158349Y-159289D01*
X1157039Y-160164D01*
X1156166Y-162206D01*
X1155729Y-163956D01*
Y-165706D01*
X1156166Y-167456D01*
X1157258Y-169206D01*
X1158568Y-170372D01*
X1160096Y-170664D01*
X1161624Y-170081D01*
X1163153Y-168331D01*
G01X1173884Y-170664D02*
Y-158998D01*
G01Y-161331D02*
X1174976Y-160164D01*
X1176068Y-159289D01*
X1177596Y-158998D01*
X1178687Y-159289D01*
X1179998Y-160164D01*
G01X1244688Y-170664D02*
Y-153164D01*
X1249054D01*
X1250801Y-154039D01*
X1252111Y-155206D01*
X1253203Y-156955D01*
X1254076Y-158998D01*
X1254294Y-161914D01*
X1254076Y-164831D01*
X1253203Y-166873D01*
X1252111Y-168623D01*
X1250801Y-169789D01*
X1249054Y-170664D01*
X1244688D01*
G01X1263716Y-162789D02*
X1270703D01*
X1270048Y-160747D01*
X1268956Y-159581D01*
X1267428Y-158998D01*
X1265899Y-159289D01*
X1264589Y-160164D01*
X1263716Y-162206D01*
X1263279Y-163956D01*
Y-165706D01*
X1263716Y-167456D01*
X1264808Y-169206D01*
X1266118Y-170372D01*
X1267646Y-170664D01*
X1269174Y-170081D01*
X1270703Y-168331D01*
G01X1281216Y-168623D02*
X1282308Y-169789D01*
X1283836Y-170664D01*
X1285146D01*
X1286456Y-170081D01*
X1287329Y-169206D01*
X1287766Y-168040D01*
X1287548Y-166289D01*
X1286674Y-165414D01*
X1282744Y-163664D01*
X1281871Y-161622D01*
X1282308Y-160164D01*
X1283181Y-159289D01*
X1284491Y-158998D01*
X1285801Y-159289D01*
X1287111Y-160164D01*
G01X1301991Y-158998D02*
Y-170664D01*
G01Y-154331D02*
X1301554Y-154039D01*
Y-153456D01*
X1301991Y-153164D01*
X1302428Y-153456D01*
Y-154039D01*
X1301991Y-154331D01*
G01X1316434Y-175039D02*
X1317963Y-176206D01*
X1319709Y-176497D01*
X1321237Y-176206D01*
X1322548Y-174748D01*
X1323421Y-172706D01*
Y-158998D01*
G01Y-161331D02*
X1322548Y-160164D01*
X1321237Y-159289D01*
X1319709Y-158998D01*
X1317963Y-159581D01*
X1316871Y-160747D01*
X1315997Y-162789D01*
X1315561Y-164831D01*
X1315779Y-166581D01*
X1316653Y-168623D01*
X1317963Y-170081D01*
X1319709Y-170664D01*
X1321019Y-170372D01*
X1322548Y-169206D01*
X1323421Y-168040D01*
G01X1333279Y-170664D02*
Y-158998D01*
G01Y-161914D02*
X1334153Y-160456D01*
X1335463Y-159289D01*
X1337209Y-158998D01*
X1338737Y-159289D01*
X1340048Y-160456D01*
X1340703Y-162497D01*
Y-170664D01*
G01X1351216Y-162789D02*
X1358203D01*
X1357548Y-160747D01*
X1356456Y-159581D01*
X1354928Y-158998D01*
X1353399Y-159289D01*
X1352089Y-160164D01*
X1351216Y-162206D01*
X1350779Y-163956D01*
Y-165706D01*
X1351216Y-167456D01*
X1352308Y-169206D01*
X1353618Y-170372D01*
X1355146Y-170664D01*
X1356674Y-170081D01*
X1358203Y-168331D01*
G01X1368934Y-170664D02*
Y-158998D01*
G01Y-161331D02*
X1370026Y-160164D01*
X1371118Y-159289D01*
X1372646Y-158998D01*
X1373737Y-159289D01*
X1375048Y-160164D01*
G01X1266991Y-215664D02*
X1265244Y-215372D01*
X1263716Y-214206D01*
X1262406Y-212456D01*
X1261532Y-210414D01*
X1261096Y-208081D01*
Y-205747D01*
X1261532Y-203414D01*
X1262406Y-201372D01*
X1263716Y-199623D01*
X1265244Y-198456D01*
X1266991Y-198164D01*
X1268737Y-198456D01*
X1270266Y-199623D01*
X1271576Y-201372D01*
X1272450Y-203414D01*
X1272886Y-205747D01*
Y-208081D01*
X1272450Y-210414D01*
X1271576Y-212456D01*
X1270266Y-214206D01*
X1268737Y-215372D01*
X1266991Y-215664D01*
G01X1268737Y-210997D02*
X1271358Y-215664D01*
G01X1279688Y-198164D02*
Y-210706D01*
X1280561Y-213331D01*
X1282308Y-215081D01*
X1284491Y-215664D01*
X1286674Y-215081D01*
X1288421Y-213331D01*
X1289294Y-210706D01*
Y-198164D01*
G01X1299371D02*
X1304611D01*
G01X1301991D02*
Y-215664D01*
G01X1299371D02*
X1304611D01*
G01X1314469D02*
Y-198164D01*
X1324513Y-215664D01*
Y-198164D01*
G01X1341794Y-199623D02*
X1340484Y-198747D01*
X1338956Y-198164D01*
X1337209D01*
X1335244Y-199039D01*
X1333716Y-200497D01*
X1332624Y-202248D01*
X1331751Y-205164D01*
X1331532Y-207789D01*
X1331969Y-210414D01*
X1332624Y-212164D01*
X1333934Y-213914D01*
X1335463Y-215081D01*
X1336991Y-215664D01*
X1338519D01*
X1340048Y-215081D01*
X1341358Y-214206D01*
X1342450Y-213040D01*
G01X1354491Y-215664D02*
Y-207789D01*
X1350124Y-198164D01*
G01X1358858D02*
X1354491Y-207789D01*
G01X1415691Y-198164D02*
X1413944Y-198747D01*
X1412634Y-200206D01*
X1411761Y-201955D01*
X1411106Y-204289D01*
X1410888Y-206914D01*
X1411106Y-209539D01*
X1411761Y-211873D01*
X1412634Y-213623D01*
X1413944Y-215081D01*
X1415691Y-215664D01*
X1417437Y-215081D01*
X1418748Y-213623D01*
X1419621Y-211873D01*
X1420276Y-209539D01*
X1420494Y-206914D01*
X1420276Y-204289D01*
X1419621Y-201955D01*
X1418748Y-200206D01*
X1417437Y-198747D01*
X1415691Y-198164D01*
G01X1429043Y-208373D02*
X1430571Y-206331D01*
X1431881Y-205164D01*
X1433628Y-204581D01*
X1435156Y-205164D01*
X1436248Y-206331D01*
X1437121Y-208081D01*
X1437339Y-210122D01*
X1437121Y-211873D01*
X1436248Y-213623D01*
X1434937Y-215081D01*
X1433409Y-215664D01*
X1431663Y-215081D01*
X1430134Y-213331D01*
X1429261Y-210706D01*
X1429043Y-207789D01*
X1429479Y-203998D01*
X1430134Y-201955D01*
X1431226Y-199914D01*
X1432754Y-198456D01*
X1434283Y-198164D01*
X1435811Y-198747D01*
X1436903Y-200206D01*
G01X1446761Y-216247D02*
X1454621Y-198164D01*
G01X1468191D02*
X1466444Y-198747D01*
X1465134Y-200206D01*
X1464261Y-201955D01*
X1463606Y-204289D01*
X1463388Y-206914D01*
X1463606Y-209539D01*
X1464261Y-211873D01*
X1465134Y-213623D01*
X1466444Y-215081D01*
X1468191Y-215664D01*
X1469937Y-215081D01*
X1471248Y-213623D01*
X1472121Y-211873D01*
X1472776Y-209539D01*
X1472994Y-206914D01*
X1472776Y-204289D01*
X1472121Y-201955D01*
X1471248Y-200206D01*
X1469937Y-198747D01*
X1468191Y-198164D01*
G01X1481979Y-213623D02*
X1483508Y-215081D01*
X1485254Y-215664D01*
X1487001Y-215081D01*
X1488529Y-213331D01*
X1489621Y-210706D01*
X1490058Y-208081D01*
Y-204873D01*
X1489621Y-202248D01*
X1488529Y-199914D01*
X1487219Y-198747D01*
X1485691Y-198164D01*
X1483944Y-198747D01*
X1482634Y-199914D01*
X1481761Y-201664D01*
X1481324Y-203998D01*
X1481761Y-206039D01*
X1482853Y-208081D01*
X1484163Y-209248D01*
X1485691Y-209539D01*
X1487437Y-208956D01*
X1488748Y-207497D01*
X1490058Y-204873D01*
G01X1499261Y-216247D02*
X1507121Y-198164D01*
G01X1516543Y-201081D02*
X1517853Y-199331D01*
X1519381Y-198456D01*
X1521128Y-198164D01*
X1523311Y-198747D01*
X1524839Y-200206D01*
X1525276Y-201955D01*
X1525058Y-203706D01*
X1524184Y-205164D01*
X1519818Y-208081D01*
X1517853Y-210122D01*
X1516543Y-213040D01*
X1516106Y-215664D01*
X1525276D01*
G01X1538191Y-198164D02*
X1536444Y-198747D01*
X1535134Y-200206D01*
X1534261Y-201955D01*
X1533606Y-204289D01*
X1533388Y-206914D01*
X1533606Y-209539D01*
X1534261Y-211873D01*
X1535134Y-213623D01*
X1536444Y-215081D01*
X1538191Y-215664D01*
X1539937Y-215081D01*
X1541248Y-213623D01*
X1542121Y-211873D01*
X1542776Y-209539D01*
X1542994Y-206914D01*
X1542776Y-204289D01*
X1542121Y-201955D01*
X1541248Y-200206D01*
X1539937Y-198747D01*
X1538191Y-198164D01*
G01X1555691Y-215664D02*
Y-198164D01*
X1553071Y-201664D01*
G01Y-215664D02*
X1558311D01*
G01X1572754D02*
X1573191Y-211873D01*
X1573846Y-208664D01*
X1574719Y-205747D01*
X1575811Y-202539D01*
X1577558Y-198164D01*
X1568824D01*
G01X1463388Y-170664D02*
Y-153164D01*
X1467754D01*
X1469501Y-154039D01*
X1470811Y-155206D01*
X1471903Y-156955D01*
X1472776Y-158998D01*
X1472994Y-161914D01*
X1472776Y-164831D01*
X1471903Y-166873D01*
X1470811Y-168623D01*
X1469501Y-169789D01*
X1467754Y-170664D01*
X1463388D01*
G01X1489621D02*
Y-158998D01*
G01Y-161039D02*
X1488748Y-159873D01*
X1487437Y-159289D01*
X1485909Y-158998D01*
X1484381Y-159581D01*
X1483071Y-160747D01*
X1482197Y-162497D01*
X1481761Y-164831D01*
X1482197Y-167164D01*
X1483071Y-168914D01*
X1484381Y-170081D01*
X1485909Y-170664D01*
X1487437Y-170372D01*
X1488748Y-169498D01*
X1489621Y-168331D01*
G01X1503191Y-153164D02*
Y-170664D01*
G01X1500134Y-158998D02*
X1506248D01*
G01X1517416Y-162789D02*
X1524403D01*
X1523748Y-160747D01*
X1522656Y-159581D01*
X1521128Y-158998D01*
X1519599Y-159289D01*
X1518289Y-160164D01*
X1517416Y-162206D01*
X1516979Y-163956D01*
Y-165706D01*
X1517416Y-167456D01*
X1518508Y-169206D01*
X1519818Y-170372D01*
X1521346Y-170664D01*
X1522874Y-170081D01*
X1524403Y-168331D01*
G54D11*
G01X1684500Y501500D02*
Y505500D01*
X1669500Y520500D01*
Y543742D01*
X1647866Y565376D01*
X1641024D01*
X1634200Y572200D01*
X92500Y62800D03*
X95800Y71800D03*
X30500Y67000D03*
X58709Y372346D03*
X79581Y397946D03*
X93800Y516800D03*
X95500Y525500D03*
X83500Y898662D03*
X95500Y968000D03*
X185551Y21529D03*
X131600Y119100D03*
X192842Y372000D03*
X181327Y460926D03*
X176506Y539295D03*
X143000Y587000D03*
X114563Y904041D03*
X106363Y893425D03*
X140750Y1039250D03*
X125500Y992500D03*
X130601Y1411700D03*
X124874Y1442600D03*
X151874Y1449800D03*
X149955Y1431573D03*
X135374Y1464000D03*
Y1445500D03*
X105774Y1491000D03*
X120474Y1482800D03*
X132674Y1484200D03*
X124074Y1437200D03*
X220000Y80500D03*
X215500D03*
X254900Y119600D03*
X212390Y466305D03*
X204190Y455689D03*
X218000Y516600D03*
X220000Y524000D03*
X264750Y586250D03*
X197263Y901025D03*
X218100Y969700D03*
X264450Y1039250D03*
X252000Y992500D03*
X341800Y63700D03*
X340650Y69300D03*
X379500Y119500D03*
X294542Y372300D03*
X295090Y463289D03*
X341800Y516800D03*
X344000Y525300D03*
X341900Y969400D03*
X376000Y993000D03*
X373492Y1317441D03*
Y1322441D03*
Y1327441D03*
Y1332441D03*
X343688Y1317736D03*
Y1322736D03*
Y1327736D03*
Y1332736D03*
X313688D03*
Y1327736D03*
Y1322736D03*
Y1317736D03*
Y1312736D03*
X369086Y1313208D03*
X374086D03*
X379086D03*
X384086D03*
X324086D03*
X329086D03*
X334086D03*
X339086D03*
X344086D03*
X349086D03*
X354086D03*
X359086D03*
X364086D03*
X294086D03*
X299086D03*
X304086D03*
X309086D03*
X319086D03*
X373492Y1337441D03*
Y1342441D03*
Y1347441D03*
Y1352441D03*
X343688Y1337736D03*
Y1342736D03*
Y1347736D03*
Y1352736D03*
X313688D03*
Y1347736D03*
Y1342736D03*
Y1337736D03*
X323688Y1357736D03*
X328688D03*
X333688D03*
X338688D03*
X343688D03*
X348688D03*
X353688D03*
X358688D03*
X363688D03*
X368688D03*
X373688D03*
X378688D03*
X383688D03*
X298688D03*
X303688D03*
X308688D03*
X313688D03*
X318688D03*
X293688D03*
X425500Y72600D03*
X435500D03*
X430500D03*
X440500D03*
X468500Y80500D03*
X464000D03*
X437500Y134500D03*
X441500D03*
X433500D03*
X419042Y372000D03*
X466000Y516900D03*
X464801Y521156D03*
X390632Y588624D03*
X440026Y850100D03*
X445026D03*
X466100Y969200D03*
X389250Y1039250D03*
X389086Y1313208D03*
X394086D03*
X388688Y1357736D03*
X393688D03*
X503900Y119500D03*
X543242Y372300D03*
X516000Y637413D03*
X517999Y583015D03*
X564026Y850100D03*
X569026D03*
X513250Y1039250D03*
X500000Y992000D03*
X523455Y1416564D03*
X535200Y1466100D03*
X523500Y1455400D03*
X503001Y1454922D03*
X513624Y1458624D03*
X504000Y1470500D03*
X590600Y64300D03*
X589150Y69500D03*
X628000Y119500D03*
X654242Y372000D03*
X583550Y504600D03*
X592500Y525300D03*
X664651Y513000D03*
X666900Y665400D03*
X637750Y586250D03*
X585904Y900960D03*
X589904D03*
X593904D03*
X597904D03*
X601904D03*
X590200Y969500D03*
X712214Y82500D03*
X709000Y79500D03*
X711352Y26875D03*
X715205Y27012D03*
X705171Y16254D03*
X753473Y138459D03*
X698600Y511100D03*
X716400Y525200D03*
X752200Y572300D03*
X709871Y686246D03*
X718100Y738500D03*
X718200Y744000D03*
X723000Y739200D03*
X723300Y743700D03*
X728175Y741300D03*
X728100Y745500D03*
X680526Y850100D03*
X685526D03*
X701700Y872700D03*
X714500Y870100D03*
X723600Y872400D03*
X712760Y915137D03*
X727600Y872300D03*
X733895Y901054D03*
X754000Y884524D03*
X757600Y884400D03*
X714400Y969600D03*
X759249Y1008800D03*
X759700Y1138600D03*
X759762Y1135000D03*
X742880Y1422632D03*
X739532Y1425934D03*
X745000Y1463000D03*
X756332Y1465934D03*
X745032Y1468534D03*
X732232Y1477094D03*
X718900Y1472800D03*
X835165Y470414D03*
X787971Y466121D03*
X791971D03*
X787971Y461921D03*
X791971D03*
X787971Y457721D03*
X791971D03*
X827313Y464805D03*
X827361Y459317D03*
X832417Y459017D03*
X812282Y448094D03*
X815255Y451343D03*
X808395Y454315D03*
X858740Y486430D03*
X794883Y639984D03*
X798475Y640227D03*
X863430Y618590D03*
X788160Y666220D03*
X814320Y651120D03*
X813980Y647430D03*
X860360Y605900D03*
X824618Y614617D03*
X827750Y611798D03*
X791530Y614700D03*
X791680Y619050D03*
X799900Y636300D03*
X807440Y629910D03*
X802900Y634000D03*
X837709Y681095D03*
X789442Y681063D03*
X796200Y682400D03*
X791243Y668081D03*
X778627Y735644D03*
X778683Y745049D03*
X791500Y764500D03*
X795300Y764900D03*
X815469Y811029D03*
X815330Y807050D03*
X858500Y845700D03*
X858100Y850000D03*
X848300Y847700D03*
X804200Y798200D03*
X811372Y795900D03*
X808372Y797900D03*
X805372Y801700D03*
X801300Y924300D03*
X799303Y927296D03*
X844800Y895902D03*
X845732Y891713D03*
X848400Y974100D03*
X836953Y1023500D03*
X842700Y1071900D03*
X782712Y1211404D03*
Y1206904D03*
X772601Y1223511D03*
Y1219011D03*
Y1214511D03*
X777101Y1223511D03*
X832800Y1147500D03*
X795100Y1150400D03*
X798920Y1150500D03*
X821900Y1173700D03*
X773300Y1159700D03*
X769800Y1156500D03*
X776800Y1169700D03*
X780722Y1166357D03*
X780000Y1162800D03*
X772361Y1451972D03*
X882823Y331182D03*
X909236Y333242D03*
X906486Y330524D03*
X910330Y363490D03*
X908340Y360430D03*
X870400Y454315D03*
X870200Y631500D03*
X883030Y611940D03*
X878600Y615600D03*
X879600Y621600D03*
X878400Y626200D03*
X866655Y855100D03*
X870200Y852203D03*
X872600Y798700D03*
X1054918Y1330439D03*
Y1325739D03*
Y1386039D03*
Y1353539D03*
Y1358239D03*
Y1381339D03*
X1020500Y1500014D03*
X1037550Y1475814D03*
X1136100Y460288D03*
X1147440Y473040D03*
X1143720Y468520D03*
X1143420Y472900D03*
X1139590Y468380D03*
X1139330Y472820D03*
X1135410Y468380D03*
X1135310Y472820D03*
X1130800Y472900D03*
X1131800Y446800D03*
X1136000Y446849D03*
X1092000Y448400D03*
X1088000Y448500D03*
X1103100Y457300D03*
X1095100Y455800D03*
X1149964Y481623D03*
X1138900Y584900D03*
X1125025Y621993D03*
X1141370Y905550D03*
X1101600Y953700D03*
X1075030Y1323078D03*
X1096280Y1288150D03*
X1092475Y1287971D03*
X1099112Y1391273D03*
X1099100Y1375200D03*
X1099112Y1383273D03*
X1099100Y1371200D03*
X1117362Y1406073D03*
X1134112Y1363273D03*
X1122112D03*
X1156110Y473330D03*
X1152600Y468470D03*
X1245567Y420602D03*
X1201000Y447000D03*
X1200500Y452000D03*
X1150900Y485100D03*
X1177100Y495300D03*
X1232490Y664290D03*
X1236690D03*
X1171700Y603700D03*
X1172500Y599700D03*
X1169125Y581776D03*
X1166550Y579200D03*
X1177350Y597792D03*
X1212587Y740895D03*
Y736695D03*
Y732495D03*
X1232490Y668490D03*
X1212587Y728295D03*
X1236690Y668490D03*
X1212587Y724095D03*
X1232490Y672690D03*
X1212587Y719895D03*
X1236690Y672690D03*
X1206414Y704261D03*
X1209931Y701608D03*
X1207468Y697962D03*
X1210283Y695565D03*
X1212587Y749295D03*
Y745095D03*
X1232490Y685290D03*
X1179129Y672187D03*
X1232490Y681090D03*
X1190995Y776395D03*
X1186690Y791440D03*
X1217111Y825000D03*
X1173990Y797760D03*
X1177300Y804960D03*
X1180520Y790880D03*
X1179690Y798020D03*
X1157556Y932754D03*
X1184778Y912848D03*
X1180090Y896524D03*
X1181550Y906100D03*
X1184750Y889200D03*
Y896300D03*
X1155600Y1074500D03*
X1308000Y35000D03*
X1261100Y16600D03*
X1264700Y16400D03*
X1256800Y132400D03*
X1262600Y119700D03*
X1262945Y377600D03*
X1294624Y358802D03*
X1247949Y423302D03*
X1250648Y425686D03*
X1245959Y435527D03*
X1265295Y421223D03*
X1257000Y434600D03*
X1325500Y504750D03*
X1312000Y501500D03*
X1272182Y571361D03*
X1247588Y842190D03*
X1325500Y907000D03*
Y957250D03*
X1262400Y1024700D03*
X1260000Y993500D03*
X1314375Y1424375D03*
X1282374Y1445500D03*
Y1464000D03*
X1296374Y1430700D03*
X1297089Y1450307D03*
X1436000Y48500D03*
X1376700Y136000D03*
X1394200Y113700D03*
X1341324Y372244D03*
X1362514Y397100D03*
X1436000Y501500D03*
X1383952Y573102D03*
X1341324Y825000D03*
X1362500Y851922D03*
X1386900Y1024600D03*
X1383200Y992700D03*
X1501300Y136100D03*
X1511400Y119500D03*
X1465536Y372244D03*
X1449500Y504750D03*
X1511200Y572300D03*
X1465536Y825000D03*
X1443992Y904962D03*
X1450100Y959500D03*
X1511400Y1024600D03*
X1506000Y993000D03*
X1557500Y35000D03*
X1625300Y136000D03*
X1616100Y203786D03*
X1589749Y372244D03*
X1574000Y504750D03*
X1560500Y501500D03*
X1591400Y825000D03*
X1572900Y902900D03*
X1574000Y957250D03*
X1684500Y48500D03*
X1635300Y119600D03*
X1712525Y191268D03*
X1698000Y504750D03*
X1684500Y501500D03*
X1634200Y572200D03*
X1713961Y825000D03*
X1709500Y900700D03*
X1698000Y957250D03*
X1635100Y1024700D03*
X1631500Y994000D03*
X1676511Y1292495D03*
X1719726Y1402700D03*
X1656250Y1461250D03*
X1662626Y1464000D03*
Y1445500D03*
X1674926Y1447400D03*
X1676626Y1432000D03*
X1794300Y63400D03*
X1749700Y135600D03*
X1759600Y119500D03*
X1805142Y372600D03*
X1753631Y405830D03*
X1724096Y464344D03*
X1746959Y459107D03*
X1808500Y501500D03*
X1759750Y587000D03*
X1798500Y898662D03*
X1759300Y1024900D03*
X1756000Y993500D03*
X1810426Y1476200D03*
X1868600Y68922D03*
X1872900Y49000D03*
X1885508Y77413D03*
X1891300Y49400D03*
X1834018Y169783D03*
X1822000Y504750D03*
X1848500Y504000D03*
X1883300Y530000D03*
X1853000Y504000D03*
X1880500Y540500D03*
X1838174Y825000D03*
X1820700Y940600D03*
X1848500Y940200D03*
X1829563Y904041D03*
X1821363Y893425D03*
X1822000Y957250D03*
X1848500Y957000D03*
X1875800Y981000D03*
X1827600Y970700D03*
X1824826Y1470900D03*
X1822326Y1481600D03*
X1919000Y51000D03*
X1922400Y470400D03*
X1923600Y913525D03*
X1914500Y902000D03*
X1918800Y1112100D03*
G54D21*
G01X92500Y62800D02*
X95800D01*
X171512Y138512D01*
Y141323D01*
X209559Y179370D01*
X625171D01*
X776506Y330705D01*
Y438874D01*
X793981Y456349D01*
Y514948D01*
X755300Y553629D01*
Y659000D01*
X718100Y696200D01*
Y738500D01*
G01X58709Y372346D02*
X73826Y387463D01*
X213597D01*
X231967Y405833D01*
X274331D01*
X280800Y412302D01*
X685002D01*
X722365Y449665D01*
X768850D01*
X785306Y466121D01*
X787971D01*
G01X701700Y872700D02*
Y856810D01*
X684300Y839410D01*
Y706572D01*
X609103Y631375D01*
X330924D01*
X330773Y631224D01*
X208913D01*
X171512Y593823D01*
Y588848D01*
X119179Y536515D01*
X110708D01*
X106322Y532129D01*
Y529322D01*
X93800Y516800D01*
G01X585904Y900960D02*
X559258Y927606D01*
X228924D01*
X211160Y945370D01*
X118110D01*
X95500Y967980D01*
Y968000D01*
G01X192842Y372000D02*
X203080D01*
X234190Y403110D01*
X275735D01*
X283200Y410575D01*
X686275D01*
X723640Y447940D01*
X769582D01*
X785670Y464028D01*
X789878D01*
X791971Y466121D01*
G01X124874Y1442600D02*
X121274Y1439000D01*
Y1425200D01*
X133862Y1412612D01*
Y1274138D01*
X183500Y1224500D01*
X677700D01*
X767987Y1134213D01*
Y871670D01*
X776213Y863444D01*
Y839599D01*
X780712Y835100D01*
Y757078D01*
X788212Y749578D01*
Y682293D01*
X789442Y681063D01*
G01X220000Y80500D02*
X220641D01*
X317786Y177645D01*
X625886D01*
X778231Y329990D01*
Y437819D01*
X795706Y455294D01*
Y515663D01*
X757025Y554344D01*
Y659715D01*
X720600Y696140D01*
Y741600D01*
X718200Y744000D01*
G01X714500Y870100D02*
Y865200D01*
X688800Y839500D01*
Y708632D01*
X608068Y627900D01*
X330089D01*
X296012Y593823D01*
Y591627D01*
X220985Y516600D01*
X218000D01*
G01X218100Y969700D02*
Y968472D01*
X257076Y929496D01*
X561368D01*
X589904Y900960D01*
G01X341800Y63700D02*
X345200D01*
X353280Y71780D01*
Y78249D01*
X450691Y175660D01*
X626341D01*
X780216Y329535D01*
Y437260D01*
X797690Y454734D01*
Y516485D01*
X760200Y553975D01*
Y658980D01*
X723000Y696180D01*
Y739200D01*
G01X294542Y372300D02*
X308621D01*
X345171Y408850D01*
X687560D01*
X724820Y446110D01*
X770798D01*
X786609Y461921D01*
X787971D01*
G01X723600Y872400D02*
Y870868D01*
X692700Y839968D01*
Y706460D01*
X611320Y625080D01*
X446527D01*
X418191Y596744D01*
Y589593D01*
X345398Y516800D01*
X341800D01*
G01X341900Y969400D02*
X380079Y931221D01*
X563643D01*
X593904Y900960D01*
G01X723300Y743700D02*
X724988Y742012D01*
Y696632D01*
X763200Y658420D01*
Y553415D01*
X800244Y516371D01*
Y454824D01*
X781941Y436521D01*
Y328820D01*
X626939Y173818D01*
X563568D01*
X470250Y80500D01*
X468500D01*
G01X419042Y372000D02*
X430610D01*
X465735Y407125D01*
X688275D01*
X724930Y443780D01*
X771159D01*
X787207Y459828D01*
X789878D01*
X791971Y461921D01*
G01X727600Y872300D02*
X727472D01*
X695874Y840702D01*
Y700974D01*
X534551Y539651D01*
X478301D01*
X472863Y534213D01*
Y522750D01*
X467013Y516900D01*
X466000D01*
G01X466100Y969200D02*
X502354Y932946D01*
X565918D01*
X597904Y900960D01*
G01X543242Y372300D02*
X556087D01*
X589187Y405400D01*
X690310D01*
X725205Y440295D01*
X770545D01*
X787971Y457721D01*
G01X712760Y915137D02*
X699474Y901851D01*
Y857024D01*
X682575Y840125D01*
Y707287D01*
X634628Y659340D01*
X604094D01*
X582167Y637413D01*
X516000D01*
G01X728175Y741300D02*
X727800Y740925D01*
Y696260D01*
X764925Y659135D01*
Y554435D01*
X802185Y517175D01*
Y454219D01*
X786100Y438134D01*
Y326587D01*
X661703Y202190D01*
Y138324D01*
X596502Y73123D01*
Y70202D01*
X590600Y64300D01*
G01X654242Y372000D02*
Y381037D01*
X676880Y403675D01*
X691025D01*
X722400Y435050D01*
X769300D01*
X791971Y457721D01*
G01X583550Y504600D02*
X590400D01*
X601500Y515700D01*
Y531000D01*
X657300Y586800D01*
Y638400D01*
X666900Y648000D01*
Y665400D01*
G01X709871Y686246D02*
X709500Y685875D01*
Y669600D01*
X668512Y628612D01*
Y516488D01*
X673900Y511100D01*
X698600D01*
G01X590200Y969500D02*
X594390Y965310D01*
Y908474D01*
X601904Y900960D01*
G01X712214Y82500D02*
Y95175D01*
X717000Y99961D01*
Y128872D01*
X722205Y134077D01*
Y258049D01*
X788801Y324645D01*
Y438395D01*
X803910Y453504D01*
Y517890D01*
X768000Y553800D01*
Y705600D01*
X728100Y745500D01*
G01X812282Y448094D02*
Y447723D01*
X796856Y432297D01*
Y293116D01*
X759500Y255760D01*
Y114758D01*
X730624Y85882D01*
X730610D01*
X727937Y83209D01*
Y83195D01*
X727570Y82828D01*
Y46898D01*
X723440Y42768D01*
X723439D01*
X711352Y30681D01*
Y26875D01*
G01X815255Y451343D02*
Y447054D01*
X799431Y431230D01*
Y291448D01*
X762075Y254092D01*
Y113691D01*
X731691Y83307D01*
X731677D01*
X730512Y82142D01*
Y82128D01*
X730145Y81761D01*
Y45831D01*
X715205Y30891D01*
Y27012D01*
G01X788160Y666220D02*
X784762Y669618D01*
Y748038D01*
X777300Y755500D01*
X741800D01*
X712400Y784900D01*
Y835361D01*
X753039Y876000D01*
X759037D01*
X764537Y881500D01*
Y1130225D01*
X759762Y1135000D01*
G01X754000Y884524D02*
X748996D01*
X704248Y839776D01*
Y780652D01*
X744056Y740844D01*
X773427D01*
X778627Y735644D01*
G01X778683Y745049D02*
X777434Y743800D01*
X745100D01*
X706823Y782077D01*
Y838709D01*
X750014Y881900D01*
X755100D01*
X757600Y884400D01*
G01X733895Y901054D02*
X727143D01*
X717601Y910596D01*
Y966399D01*
X714400Y969600D01*
G01X791243Y668081D02*
X786487Y672837D01*
Y748863D01*
X778987Y756363D01*
Y830713D01*
X776000Y833700D01*
Y837372D01*
X774488Y838884D01*
Y862729D01*
X766262Y870955D01*
Y1132038D01*
X759700Y1138600D01*
G01X745000Y1463000D02*
Y1454000D01*
X737220Y1446220D01*
Y1423219D01*
X744541Y1415898D01*
X799725D01*
X806098Y1409525D01*
Y1281341D01*
X755662Y1230905D01*
Y1154924D01*
X774488Y1136098D01*
Y874209D01*
X786289Y862408D01*
Y759754D01*
X793788Y752255D01*
Y684812D01*
X796200Y682400D01*
G01X833859Y272441D02*
Y273613D01*
X829325Y278147D01*
Y315537D01*
X829090Y315772D01*
Y319076D01*
X826078Y322088D01*
Y365705D01*
X816653Y375130D01*
Y431567D01*
X823951Y438865D01*
Y461443D01*
X827313Y464805D01*
G01X833859Y277953D02*
Y278288D01*
X831300Y280847D01*
Y315407D01*
X831665Y315772D01*
Y320143D01*
X828653Y323155D01*
Y366772D01*
X819228Y376197D01*
Y430500D01*
X826526Y437798D01*
Y458482D01*
X827361Y459317D01*
G01X848032Y272441D02*
X852603Y277012D01*
Y316603D01*
X854354Y318354D01*
Y319307D01*
G01X848032Y277953D02*
X843506Y282479D01*
Y319051D01*
X842712Y319845D01*
G01X848032Y286614D02*
X850563Y289145D01*
Y313593D01*
X849812Y314344D01*
Y325688D01*
X838000Y337500D01*
Y441500D01*
X835175Y444325D01*
Y470404D01*
X835165Y470414D01*
G01X848032Y292126D02*
X845521Y294637D01*
Y315149D01*
X846144Y315772D01*
Y320356D01*
X834924Y331576D01*
Y440576D01*
X832417Y443083D01*
Y459017D01*
G01X862205Y292126D02*
X859717Y294614D01*
Y315172D01*
X860912Y316367D01*
Y388610D01*
X843576Y405946D01*
Y445154D01*
X840751Y447979D01*
Y631636D01*
X842200Y633085D01*
Y648157D01*
X846963Y652920D01*
Y685601D01*
X850410Y689048D01*
Y783131D01*
X852432Y785153D01*
Y832238D01*
X848300Y836370D01*
Y847700D01*
G01X897638Y258268D02*
X894680Y261226D01*
Y289710D01*
X893115Y291275D01*
Y415731D01*
X866396Y442450D01*
X866395D01*
X865386Y443459D01*
Y467421D01*
X861522Y471285D01*
Y472713D01*
X861523Y472714D01*
Y487960D01*
X858886Y490597D01*
Y599833D01*
X863148Y604095D01*
Y618308D01*
X863430Y618590D01*
G01X869292Y268504D02*
X871825Y271037D01*
Y315700D01*
X871590Y315935D01*
Y329937D01*
X870059Y331468D01*
Y392811D01*
X853218Y409652D01*
Y462791D01*
X848476Y467533D01*
Y627674D01*
X854688Y633886D01*
Y681263D01*
X860157Y686732D01*
Y844043D01*
X858500Y845700D01*
G01X869292Y262992D02*
X873800Y267500D01*
Y313117D01*
X874165Y313482D01*
Y331018D01*
X873731Y331452D01*
Y393940D01*
X855793Y411878D01*
Y463858D01*
X851051Y468600D01*
Y626607D01*
X858410Y633966D01*
Y667225D01*
X862732Y671547D01*
Y845368D01*
X858100Y850000D01*
G01X890552Y311023D02*
X889757D01*
X888206Y312574D01*
Y418200D01*
X865681Y440725D01*
X865680D01*
X863661Y442744D01*
Y466706D01*
X858740Y471627D01*
Y486430D01*
G01X844800Y895902D02*
X842053Y893155D01*
Y873557D01*
X851853Y863757D01*
Y837786D01*
X855007Y834632D01*
Y784086D01*
X852985Y782064D01*
Y687981D01*
X849538Y684534D01*
Y636020D01*
X843326Y629808D01*
Y449047D01*
X846151Y446222D01*
Y407013D01*
X863945Y389219D01*
Y313802D01*
X864783Y312964D01*
Y295847D01*
X869292Y291338D01*
G01X845732Y891713D02*
X845200Y891181D01*
Y874656D01*
X855600Y864256D01*
Y844958D01*
X857582Y842976D01*
Y688935D01*
X852113Y683466D01*
Y634953D01*
X845901Y628741D01*
Y450114D01*
X848726Y447289D01*
Y408080D01*
X866758Y390048D01*
Y299384D01*
X869292Y296850D01*
G01X795100Y1150400D02*
Y1150485D01*
X798064Y1147521D01*
Y991824D01*
X798065Y991823D01*
Y972289D01*
X798064Y972288D01*
Y965087D01*
X799656Y963495D01*
X799657D01*
X801289Y961863D01*
Y930960D01*
X803876Y928373D01*
Y885451D01*
X815337Y873990D01*
Y853123D01*
X815338Y853122D01*
Y853121D01*
X818044Y850415D01*
Y825709D01*
X822170Y821583D01*
Y803373D01*
X819897Y801100D01*
Y666860D01*
X817299Y664262D01*
Y624676D01*
X812680Y620057D01*
Y448492D01*
X812282Y448094D01*
G01X798920Y1150500D02*
X800639Y1148781D01*
Y992891D01*
X800640Y992890D01*
Y971222D01*
X800639Y971221D01*
Y966154D01*
X800723Y966070D01*
X800724D01*
X803864Y962930D01*
Y932028D01*
X806451Y929441D01*
Y886518D01*
X817912Y875057D01*
Y854190D01*
X817913Y854189D01*
Y854188D01*
X819545Y852556D01*
X819546D01*
X820619Y851483D01*
Y826776D01*
X824745Y822650D01*
Y802306D01*
X822472Y800033D01*
Y665793D01*
X819874Y663195D01*
Y623609D01*
X815255Y618990D01*
Y451343D01*
G01X897638Y292126D02*
X895090Y294674D01*
Y416196D01*
X867111Y444175D01*
Y468136D01*
X863248Y471999D01*
Y488675D01*
X860611Y491312D01*
Y598101D01*
X864873Y602363D01*
Y612743D01*
X865590Y613460D01*
Y629850D01*
X868200Y632460D01*
Y666299D01*
X870308Y668407D01*
Y799219D01*
X872531Y801442D01*
Y847061D01*
X866655Y852937D01*
Y855100D01*
G01X794883Y639984D02*
X796489Y641590D01*
Y669548D01*
X798188Y671247D01*
Y750555D01*
X793231Y755512D01*
Y762769D01*
X791500Y764500D01*
G01X798475Y640227D02*
X798214Y640488D01*
Y668833D01*
X799913Y670532D01*
Y751270D01*
X794956Y756227D01*
Y764556D01*
X795300Y764900D01*
G01X814320Y651120D02*
X812802Y652638D01*
Y663407D01*
X816735Y667340D01*
Y804813D01*
X817906Y805984D01*
Y808592D01*
X815469Y811029D01*
G01X813980Y647430D02*
X810227Y651183D01*
Y664474D01*
X814160Y668407D01*
Y805880D01*
X815330Y807050D01*
G01X772361Y1451972D02*
X778360D01*
X814674Y1415658D01*
Y1277735D01*
X779924Y1242985D01*
Y1192534D01*
X808310Y1164148D01*
X808311D01*
X815216Y1157243D01*
Y1157242D01*
X815217Y1157241D01*
Y1152447D01*
X815216Y1152446D01*
Y972193D01*
X818440Y968969D01*
Y938603D01*
X820040Y937003D01*
X832773Y924269D01*
Y870708D01*
X841288Y862193D01*
Y853610D01*
X838790Y851112D01*
Y833750D01*
X839321Y833219D01*
Y794710D01*
X841680Y792351D01*
Y692447D01*
X838387Y689154D01*
Y685177D01*
X837709Y684499D01*
Y681095D01*
G01X815469Y811029D02*
Y849348D01*
X812763Y852054D01*
Y852055D01*
X812761Y852057D01*
Y854189D01*
X812762Y854190D01*
Y872923D01*
X801200Y884485D01*
Y924200D01*
X801300Y924300D01*
G01X815330Y807050D02*
X812843Y809537D01*
Y848332D01*
X810188Y850987D01*
Y850988D01*
X810186Y850990D01*
Y855256D01*
X810187Y855257D01*
Y871856D01*
X798064Y883979D01*
Y925875D01*
X799485Y927296D01*
X799303D01*
G01X870200Y852203D02*
Y874954D01*
X860100Y885054D01*
Y891600D01*
X855825Y895875D01*
Y900115D01*
X848400Y907540D01*
Y974100D01*
G01X890552Y282677D02*
X882139Y291090D01*
Y330498D01*
X882823Y331182D01*
G01X904725Y272835D02*
Y273425D01*
X909290Y277990D01*
Y333188D01*
X909236Y333242D01*
G01X904725Y277165D02*
Y278025D01*
X907315Y280615D01*
Y329695D01*
X906486Y330524D01*
G01X897638Y263779D02*
X897769D01*
X902194Y268204D01*
Y344418D01*
X904172Y346396D01*
Y352922D01*
X910330Y359080D01*
Y363490D01*
G01X897638Y268110D02*
X898060D01*
X900219Y270269D01*
Y346373D01*
X900196Y346396D01*
Y352286D01*
X908340Y360430D01*
G01X872600Y798700D02*
X872300Y798400D01*
Y633600D01*
X870200Y631500D01*
G01X872600Y798700D02*
X874256Y800356D01*
Y848147D01*
X870200Y852203D01*
G01X1136100Y460288D02*
X1158052D01*
X1183105Y485341D01*
Y735240D01*
X1158599Y759746D01*
Y910962D01*
X1132661Y936900D01*
X1116372D01*
X1113530Y939742D01*
G01X1115105Y720057D02*
X1117612Y722564D01*
X1136361D01*
X1154366Y704559D01*
Y577982D01*
X1155086Y577262D01*
Y492886D01*
X1147440Y485240D01*
Y473040D01*
G01X1109593Y720057D02*
X1112151Y717499D01*
X1138986D01*
X1152641Y703844D01*
Y577267D01*
X1153361Y576547D01*
Y493601D01*
X1145452Y485692D01*
Y470252D01*
X1143720Y468520D01*
G01X1119042Y712970D02*
X1121596Y715524D01*
X1138481D01*
X1150916Y703089D01*
Y576552D01*
X1151038Y576430D01*
Y528546D01*
X1150961Y528469D01*
Y494101D01*
X1150942Y494082D01*
Y493622D01*
X1143420Y486100D01*
Y472900D01*
G01X1113530Y712970D02*
X1115806D01*
X1118362Y710414D01*
X1138186D01*
X1149191Y699409D01*
Y575837D01*
X1149313Y575715D01*
Y529261D01*
X1149236Y529184D01*
Y494816D01*
X1148722Y494302D01*
Y493842D01*
X1141432Y486552D01*
Y470222D01*
X1139590Y468380D01*
G01X1115105Y705884D02*
X1117635Y708414D01*
X1137746D01*
X1147466Y698694D01*
Y575122D01*
X1147588Y575000D01*
Y529976D01*
X1147511Y529899D01*
Y495531D01*
X1146997Y495017D01*
Y494557D01*
X1139330Y486890D01*
Y472820D01*
G01X1109593Y705884D02*
X1111869D01*
X1114384Y703369D01*
X1139842D01*
X1145741Y697470D01*
Y574407D01*
X1145863Y574285D01*
Y530691D01*
X1145786Y530614D01*
Y496246D01*
X1145272Y495732D01*
Y495272D01*
X1137342Y487342D01*
Y470312D01*
X1135410Y468380D01*
G01X1119042Y698797D02*
X1121584Y701339D01*
X1138599D01*
X1144016Y695922D01*
Y573692D01*
X1144138Y573570D01*
Y531406D01*
X1144061Y531329D01*
Y496961D01*
X1135310Y488210D01*
Y472820D01*
G01X1113530Y698797D02*
X1116427Y695900D01*
X1134720D01*
X1137355Y693265D01*
Y671600D01*
X1142291Y666664D01*
Y572977D01*
X1142413Y572855D01*
Y532121D01*
X1142316Y532024D01*
Y498916D01*
X1130800Y487400D01*
Y472900D01*
G01X1131800Y446800D02*
X1134336Y449336D01*
X1162306D01*
X1193856Y480886D01*
Y728804D01*
X1194149Y729097D01*
Y730857D01*
X1212587Y749295D01*
G01Y745095D02*
X1195581Y728089D01*
Y480171D01*
X1163021Y447611D01*
X1136762D01*
X1136000Y446849D01*
G01X1180090Y896524D02*
X1178659Y895093D01*
X1177143D01*
X1168552Y886502D01*
Y762559D01*
X1186844Y744267D01*
X1186845D01*
X1188478Y742634D01*
X1188479D01*
X1191121Y739992D01*
X1191122D01*
X1192131Y738983D01*
Y738981D01*
X1192253Y738859D01*
Y729641D01*
X1192131Y729519D01*
Y481601D01*
X1161591Y451061D01*
X1100515D01*
X1100314Y451262D01*
X1094862D01*
X1092000Y448400D01*
G01X1181550Y906100D02*
X1166827Y891377D01*
Y763274D01*
X1166826Y763273D01*
Y761845D01*
X1186129Y742542D01*
X1186130D01*
X1187763Y740909D01*
X1187764D01*
X1190406Y738267D01*
Y738266D01*
X1190528Y738144D01*
Y730357D01*
X1190406Y730235D01*
Y482316D01*
X1160876Y452786D01*
X1101231D01*
X1101030Y452987D01*
X1092487D01*
X1088000Y448500D01*
G01X1101600Y953700D02*
X1130374D01*
X1138386Y945688D01*
X1139388D01*
X1164175Y920901D01*
Y919899D01*
X1164387Y919687D01*
Y761844D01*
X1185415Y740816D01*
X1185416D01*
X1187048Y739184D01*
X1187049D01*
X1188681Y737552D01*
Y737550D01*
X1188803Y737428D01*
Y731072D01*
X1188681Y730950D01*
Y483031D01*
X1160161Y454511D01*
X1101946D01*
X1101745Y454712D01*
X1096188D01*
X1095100Y455800D01*
G01X1119042Y527143D02*
Y528662D01*
X1121280Y530900D01*
X1137550D01*
X1139838Y533188D01*
Y571788D01*
X1139716Y571910D01*
Y584084D01*
X1138900Y584900D01*
G01X1115105Y691711D02*
X1117927Y688889D01*
X1134760D01*
X1135331Y688318D01*
Y632345D01*
X1125025Y622039D01*
Y621993D01*
G01X1115105Y734230D02*
X1117875Y737000D01*
X1137283D01*
X1161266Y713017D01*
Y580842D01*
X1161986Y580122D01*
Y481586D01*
X1156110Y475710D01*
Y473330D01*
G01X1109593Y734230D02*
X1112223Y731600D01*
X1139254D01*
X1159541Y711313D01*
Y580127D01*
X1160261Y579407D01*
Y484061D01*
X1154122Y477922D01*
Y469992D01*
X1152600Y468470D01*
G01X1119042Y727144D02*
X1121498Y729600D01*
X1138813D01*
X1157816Y710597D01*
Y579412D01*
X1158536Y578692D01*
Y489925D01*
X1150234Y481623D01*
X1149964D01*
G01X1113530Y727144D02*
X1113856D01*
X1116341Y724659D01*
X1136706D01*
X1153048Y708317D01*
X1153049D01*
X1154058Y707308D01*
X1154059D01*
X1154240Y707127D01*
X1154241D01*
X1156091Y705277D01*
Y578697D01*
X1156811Y577977D01*
Y491111D01*
X1150900Y485200D01*
Y485100D01*
G01X1115105Y861789D02*
X1118494Y858400D01*
X1138160D01*
X1145205Y851355D01*
Y750227D01*
X1168991Y726441D01*
Y606409D01*
X1171700Y603700D01*
G01X1109593Y861789D02*
X1112851Y865047D01*
X1137229D01*
X1147780Y854496D01*
Y751294D01*
X1171566Y727508D01*
Y608428D01*
X1174276Y605718D01*
Y601476D01*
X1172500Y599700D01*
G01X1169125Y581776D02*
Y588375D01*
X1169600Y588850D01*
Y602158D01*
X1166416Y605342D01*
Y716370D01*
X1142502Y740284D01*
Y843134D01*
X1134743Y850893D01*
X1118382D01*
X1115105Y847616D01*
G01X1109593D02*
X1113009Y844200D01*
X1137350D01*
X1139927Y841623D01*
Y739200D01*
X1163841Y715286D01*
Y581909D01*
X1166550Y579200D01*
G01X1096280Y1288150D02*
Y1202662D01*
X1112266Y1186676D01*
X1129509D01*
X1161164Y1155021D01*
Y1067567D01*
X1085688Y992091D01*
Y854219D01*
X1089150Y850757D01*
X1111964D01*
X1115105Y847616D01*
G01X1092475Y1287971D02*
X1092300Y1288146D01*
Y1203000D01*
X1111200Y1184100D01*
X1128443D01*
X1158588Y1153955D01*
Y1091044D01*
X1158589Y1091043D01*
Y1068634D01*
X1083113Y993158D01*
Y849745D01*
X1088317Y844541D01*
X1106518D01*
X1109593Y847616D01*
G01X1115105Y875962D02*
X1117870Y873197D01*
X1141606D01*
X1150355Y864448D01*
Y752361D01*
X1174141Y728575D01*
Y609495D01*
X1177336Y606300D01*
Y597778D01*
X1177350Y597792D01*
G01X1262945Y377600D02*
Y382271D01*
X1243934Y401282D01*
X1242982D01*
X1197599Y446665D01*
Y725907D01*
X1212587Y740895D01*
G01X1261100Y16600D02*
X1246200Y31500D01*
Y210800D01*
X1265727Y230327D01*
Y338175D01*
X1264236Y339666D01*
Y362018D01*
X1264235Y362019D01*
Y367715D01*
X1264237Y367717D01*
Y372963D01*
X1265727Y374453D01*
Y383131D01*
X1201858Y447000D01*
X1201000D01*
G01X1264700Y16400D02*
Y18500D01*
X1248775Y34425D01*
Y208875D01*
X1268302Y228402D01*
Y339242D01*
X1266811Y340733D01*
Y363085D01*
X1266810Y363086D01*
Y366648D01*
X1266812Y366650D01*
Y371896D01*
X1268302Y373386D01*
Y384198D01*
X1200500Y452000D01*
G01X1212587Y736695D02*
X1204079Y728187D01*
Y713503D01*
X1221288Y696294D01*
Y517049D01*
X1280337Y458000D01*
X1313635D01*
X1327612Y444023D01*
Y385956D01*
X1341324Y372244D01*
G01X1212587Y732495D02*
X1206254Y726162D01*
Y715165D01*
X1223013Y698406D01*
Y517764D01*
X1281052Y459725D01*
X1335412D01*
X1413791Y381346D01*
X1456434D01*
X1465536Y372244D01*
G01X1212587Y728295D02*
X1208620Y724328D01*
Y717085D01*
X1224738Y700967D01*
Y518479D01*
X1281767Y461450D01*
X1484750D01*
X1573956Y372244D01*
X1589749D01*
G01X1753631Y405830D02*
X1750558Y408903D01*
X1703008D01*
X1697416Y414495D01*
X1537395D01*
X1488715Y463175D01*
X1282482D01*
X1226463Y519194D01*
Y702630D01*
X1210410Y718683D01*
Y721918D01*
X1212587Y724095D01*
G01Y719895D02*
X1228188Y704294D01*
Y519909D01*
X1283197Y464900D01*
X1492501D01*
X1539277Y418124D01*
X1696227D01*
X1703723Y410628D01*
X1767114D01*
X1805142Y372600D01*
G01X1616100Y203786D02*
X1606088Y213798D01*
X1490030D01*
X1357568Y346260D01*
X1292313D01*
X1284802Y353771D01*
Y437621D01*
X1201428Y520995D01*
Y699275D01*
X1206414Y704261D01*
G01X1712525Y191268D02*
X1700197Y178940D01*
X1647033D01*
X1609882Y216091D01*
X1490980D01*
X1358518Y348553D01*
X1293263D01*
X1287095Y354721D01*
Y438571D01*
X1204114Y521552D01*
Y697805D01*
X1207917Y701608D01*
X1209931D01*
G01X1207468Y697962D02*
X1206638Y697132D01*
Y522027D01*
X1243202Y485464D01*
X1289216Y439450D01*
Y355600D01*
X1294142Y350674D01*
X1359397D01*
X1491859Y218212D01*
X1611091D01*
X1634216Y195087D01*
X1742891D01*
X1765126Y172852D01*
X1830949D01*
X1834018Y169783D01*
G01X1210283Y695565D02*
X1208363Y693645D01*
Y522937D01*
X1291078Y440222D01*
Y356372D01*
X1294914Y352536D01*
X1360169D01*
X1492631Y220074D01*
X1611669D01*
X1634931Y196812D01*
X1743800D01*
X1765898Y174714D01*
X1837379D01*
X1862514Y149579D01*
Y124256D01*
X1877767Y109003D01*
Y65330D01*
X1871405Y58968D01*
Y50495D01*
X1872900Y49000D01*
G01X1232490Y664290D02*
Y637870D01*
X1323430Y546930D01*
Y506820D01*
X1325500Y504750D01*
G01X1449500D02*
X1448512Y505738D01*
Y534693D01*
X1371118Y612087D01*
X1266973D01*
X1236690Y642370D01*
Y664290D01*
G01X1574000Y504750D02*
Y512189D01*
X1573012Y513177D01*
Y534405D01*
X1488417Y619000D01*
X1265560D01*
X1241124Y643436D01*
Y663456D01*
X1238302Y666278D01*
X1234702D01*
X1232490Y668490D01*
G01X1236690D02*
X1239231D01*
X1244181Y663540D01*
Y644879D01*
X1265560Y623500D01*
X1608130D01*
X1697012Y534618D01*
Y513177D01*
X1698000Y512189D01*
Y504750D01*
G01X1822000D02*
X1818000Y508750D01*
Y537842D01*
X1728842Y627000D01*
X1267365D01*
X1247717Y646648D01*
Y663676D01*
X1240691Y670702D01*
X1234478D01*
X1232490Y672690D01*
G01X1236690D02*
X1241264D01*
X1251015Y662939D01*
Y645790D01*
X1266305Y630500D01*
X1745500D01*
X1823500Y552500D01*
Y529000D01*
X1848500Y504000D01*
G01X1232490Y685290D02*
Y753784D01*
X1217124Y769150D01*
X1191739D01*
X1172002Y788887D01*
Y876452D01*
X1184750Y889200D01*
G01Y896300D02*
X1170277Y881827D01*
Y788172D01*
X1191828Y766621D01*
X1215318D01*
X1230502Y751437D01*
Y683078D01*
X1232490Y681090D01*
G01X1190995Y776395D02*
X1197770Y783170D01*
X1356170D01*
X1371300Y798300D01*
X1687261D01*
X1713961Y825000D01*
G01X1186690Y791440D02*
X1339240D01*
X1356000Y808200D01*
X1683812D01*
X1712261Y836649D01*
X1826525D01*
X1838174Y825000D01*
G01X1217111D02*
X1178700D01*
X1173990Y820290D01*
Y797760D01*
G01X1341324Y825000D02*
X1321284Y804960D01*
X1177300D01*
G01X1465536Y825000D02*
X1357200D01*
X1333200Y801000D01*
X1179900D01*
X1178908Y800008D01*
X1178867D01*
X1176900Y798041D01*
Y794400D01*
X1180420Y790880D01*
X1180520D01*
G01X1591400Y825000D02*
X1468838D01*
X1465806Y821968D01*
X1356608D01*
X1332660Y798020D01*
X1179690D01*
G01X1245567Y420602D02*
X1258887Y407282D01*
Y400213D01*
X1270877Y388223D01*
Y372319D01*
X1269387Y370829D01*
Y365583D01*
X1269385Y365581D01*
Y364153D01*
X1269386Y364152D01*
Y341801D01*
X1270877Y340310D01*
Y225909D01*
X1256800Y211832D01*
Y132400D01*
G01X1247949Y423302D02*
X1263603Y407648D01*
Y403603D01*
X1274694Y392512D01*
Y373696D01*
X1271112Y370114D01*
Y364868D01*
X1271111Y364867D01*
Y342516D01*
X1276253Y337374D01*
X1329832D01*
X1384500Y282706D01*
Y143800D01*
X1376700Y136000D01*
G01X1501300Y136100D02*
Y174674D01*
X1344478Y331496D01*
X1338150D01*
X1330547Y339099D01*
X1276968D01*
X1272837Y343230D01*
Y362723D01*
X1272836Y362724D01*
Y364152D01*
X1272837Y364153D01*
Y369399D01*
X1276419Y372981D01*
Y399555D01*
X1250911Y425063D01*
Y425423D01*
X1250648Y425686D01*
G01X1625300Y136000D02*
Y153700D01*
X1570787Y208213D01*
X1470201D01*
X1341398Y337016D01*
X1335070D01*
X1331262Y340824D01*
X1277683D01*
X1274562Y343945D01*
Y368684D01*
X1278144Y372266D01*
Y400270D01*
X1253400Y425014D01*
Y428086D01*
X1245959Y435527D01*
G01X1749700Y135600D02*
Y138300D01*
X1723205Y164795D01*
X1621379D01*
X1576236Y209938D01*
X1476580D01*
X1347777Y338741D01*
X1335785D01*
X1331977Y342549D01*
X1278399D01*
X1276287Y344661D01*
Y367969D01*
X1279869Y371551D01*
Y406649D01*
X1265295Y421223D01*
G01X1257000Y434600D02*
Y434610D01*
X1281594Y410016D01*
Y370836D01*
X1278012Y367254D01*
Y345376D01*
X1279114Y344274D01*
X1332692D01*
X1336500Y340466D01*
X1351144D01*
X1479624Y211986D01*
X1578476D01*
X1621799Y168663D01*
X1808828D01*
X1819991Y157500D01*
X1848600D01*
X1858800Y147300D01*
Y118800D01*
X1872525Y105075D01*
Y86024D01*
X1874500Y84049D01*
Y74822D01*
X1868600Y68922D01*
G01X1325500Y957250D02*
Y907000D01*
G01X1450100Y959500D02*
Y957850D01*
X1443992Y951742D01*
Y904962D01*
G01X1572900Y902900D02*
Y956150D01*
X1574000Y957250D01*
G01X1698000D02*
X1699520Y955730D01*
Y910680D01*
X1709500Y900700D01*
G01X1656250Y1461250D02*
Y1446008D01*
X1690500Y1411758D01*
Y1306484D01*
X1676511Y1292495D01*
G01X1822000Y957250D02*
X1820700Y955950D01*
Y940600D01*
G01X1848500Y957000D02*
Y940200D01*
G54D12*
X384055Y1330472D03*
Y1320472D03*
X354055Y1330472D03*
X364055D03*
X354055Y1320472D03*
X364055D03*
X324055Y1330472D03*
X334055D03*
X324055Y1320472D03*
X334055D03*
X304055Y1330472D03*
Y1320472D03*
X294055Y1330472D03*
Y1320472D03*
X384055Y1340472D03*
Y1350472D03*
X354055Y1340472D03*
Y1350472D03*
X364055Y1340472D03*
Y1350472D03*
X324055Y1340472D03*
Y1350472D03*
X334055Y1340472D03*
Y1350472D03*
X304055D03*
Y1340472D03*
X294055Y1350472D03*
Y1340472D03*
X474055Y1330472D03*
X484055D03*
X474055Y1320472D03*
X484055D03*
X444055Y1330472D03*
X454055D03*
X444055Y1320472D03*
X454055D03*
X414055Y1330472D03*
X424055D03*
X414055Y1320472D03*
X424055D03*
X394055Y1330472D03*
Y1320472D03*
X474055Y1340472D03*
Y1350472D03*
X484055Y1340472D03*
Y1350472D03*
X444055Y1340472D03*
Y1350472D03*
X454055Y1340472D03*
Y1350472D03*
X414055Y1340472D03*
Y1350472D03*
X424055Y1340472D03*
Y1350472D03*
X394055Y1340472D03*
Y1350472D03*
G54D13*
X462000Y1382985D03*
Y1372985D03*
Y1362985D03*
X474000Y1382985D03*
Y1372985D03*
Y1362985D03*
X426000D03*
X450000Y1372985D03*
Y1382985D03*
X414000Y1372985D03*
X450000Y1362985D03*
X438000Y1372985D03*
X414000Y1362985D03*
X438000D03*
X426000Y1372985D03*
X438000Y1382985D03*
X414000D03*
X426000D03*
X498000Y1332985D03*
X510000Y1344485D03*
X498000Y1352985D03*
X522000Y1344485D03*
X498000Y1342985D03*
X510000Y1354485D03*
X522000D03*
X510000Y1364485D03*
X522000D03*
X510000Y1374485D03*
Y1384485D03*
X522000Y1374485D03*
Y1384485D03*
X498000Y1382985D03*
Y1372985D03*
X486000Y1382985D03*
Y1372985D03*
X498000Y1362985D03*
X486000D03*
X658200Y1329200D03*
X666100D03*
X581800Y1321200D03*
Y1329100D03*
X589700D03*
Y1321200D03*
X594800Y1313500D03*
X597600Y1321200D03*
Y1329100D03*
X610600Y1313500D03*
Y1305600D03*
Y1297600D03*
X602700Y1313500D03*
Y1305600D03*
Y1297600D03*
X629200Y1329100D03*
X605500Y1321200D03*
X613400D03*
X605500Y1329100D03*
X613400D03*
X621300D03*
X666100Y1360800D03*
Y1368700D03*
Y1376600D03*
Y1352900D03*
X658200Y1360800D03*
Y1368700D03*
Y1376600D03*
Y1352900D03*
X666100Y1337100D03*
Y1345000D03*
X658200Y1337100D03*
Y1345000D03*
X581800Y1376500D03*
Y1384400D03*
Y1392300D03*
Y1360700D03*
Y1368600D03*
Y1352800D03*
Y1344900D03*
Y1337000D03*
X589700Y1392300D03*
Y1400200D03*
Y1344900D03*
Y1352800D03*
Y1384400D03*
Y1376500D03*
Y1368600D03*
Y1360700D03*
Y1337000D03*
X597600Y1400200D03*
Y1408100D03*
Y1360700D03*
Y1368600D03*
Y1392300D03*
Y1376500D03*
Y1384400D03*
Y1352800D03*
Y1337000D03*
Y1344900D03*
X629200D03*
X621300D03*
X613400D03*
X605500D03*
Y1360700D03*
X613400D03*
X621300D03*
X629200D03*
X605500Y1352800D03*
X613400D03*
X621300D03*
X629200D03*
Y1368600D03*
Y1376500D03*
X605500Y1408100D03*
Y1400200D03*
Y1392300D03*
Y1384400D03*
Y1376500D03*
Y1368600D03*
X613400Y1400200D03*
Y1392300D03*
Y1384400D03*
Y1376500D03*
Y1368600D03*
X621300Y1376500D03*
Y1368600D03*
X629200Y1337000D03*
X613400D03*
X621300D03*
X605500D03*
X613400Y1408100D03*
X705600Y1329200D03*
X697700Y1321300D03*
Y1329200D03*
X689800D03*
Y1321300D03*
X693800Y1313900D03*
Y1306000D03*
X685900D03*
X678000D03*
Y1313900D03*
X685900D03*
X681900Y1321300D03*
X674000D03*
Y1329200D03*
X681900D03*
X693800Y1298000D03*
X685900D03*
X678000D03*
X768867Y1311110D03*
Y1335110D03*
Y1327110D03*
Y1319110D03*
X705600Y1337100D03*
Y1360800D03*
Y1352900D03*
Y1345000D03*
Y1376600D03*
Y1368700D03*
X699600Y1408200D03*
Y1392400D03*
Y1400300D03*
X697700Y1345000D03*
Y1360800D03*
Y1368700D03*
Y1376600D03*
X697100Y1384600D03*
X697700Y1352900D03*
Y1337100D03*
X691700Y1408200D03*
Y1400300D03*
X675900D03*
X683800D03*
Y1408200D03*
X675900D03*
X689800Y1352900D03*
Y1384500D03*
Y1376600D03*
X691700Y1392400D03*
X689800Y1368700D03*
Y1360800D03*
X674000D03*
X681900D03*
Y1368700D03*
X674000D03*
X675900Y1392400D03*
X683800D03*
X674000Y1376600D03*
X681900D03*
Y1384500D03*
X674000D03*
Y1352900D03*
X681900D03*
X689800Y1345000D03*
Y1337100D03*
X681900D03*
X674000D03*
X681900Y1345000D03*
X674000D03*
X768867Y1383110D03*
Y1359110D03*
Y1367110D03*
Y1351110D03*
Y1343110D03*
Y1391110D03*
Y1399110D03*
Y1375110D03*
X786200Y1334100D03*
X794200D03*
X801000Y1333800D03*
X786200Y1326100D03*
X794200D03*
X776867Y1311110D03*
Y1335110D03*
Y1327110D03*
Y1319110D03*
X775600Y1302400D03*
X801000Y1325800D03*
X790056Y1297863D03*
X798056D03*
X782056D03*
X834000Y1324500D03*
Y1317500D03*
Y1310500D03*
Y1303500D03*
X827000D03*
X820000D03*
X827000Y1310500D03*
X820000D03*
X827000Y1317500D03*
X820000D03*
X827000Y1324500D03*
X820000D03*
X776867Y1399110D03*
X790330Y1407929D03*
X782330D03*
X798330D03*
X795000Y1377900D03*
X786600Y1378100D03*
X790950Y1372703D03*
X776867Y1383110D03*
Y1359110D03*
X782950Y1372703D03*
X776867Y1367110D03*
Y1375110D03*
X798950Y1372703D03*
X776867Y1391110D03*
X790223Y1339930D03*
X782223Y1339430D03*
X798223Y1339930D03*
X776867Y1351110D03*
Y1343110D03*
X834000Y1386000D03*
Y1379000D03*
Y1363000D03*
Y1356000D03*
Y1349000D03*
Y1342000D03*
X827000D03*
X820000D03*
X827000Y1349000D03*
X820000D03*
X827000Y1356000D03*
X820000D03*
X827000Y1363000D03*
X820000D03*
X827000Y1379000D03*
X820000D03*
X827000Y1386000D03*
X820000D03*
X827000Y1393000D03*
X820000D03*
X958200Y1303900D03*
X942400D03*
X950300D03*
X934500D03*
X926600D03*
X958200Y1311800D03*
X926600D03*
X934500D03*
X950300D03*
X942400D03*
X903500Y1319400D03*
X950300Y1319700D03*
X958200D03*
X934500D03*
X942400D03*
X926600D03*
X918700D03*
X910800D03*
X887800Y1327100D03*
X934700Y1327500D03*
X895200D03*
X903100D03*
X911000D03*
X926800D03*
X918900D03*
X887800Y1335000D03*
X886400Y1368100D03*
Y1376000D03*
X894300D03*
Y1368100D03*
X934700Y1335400D03*
X926800D03*
X918900D03*
X895200D03*
X903100D03*
X911000D03*
X890400Y1358900D03*
X887800Y1350800D03*
Y1342900D03*
X937300Y1359300D03*
X934700Y1343300D03*
Y1351200D03*
X926800Y1343300D03*
Y1351200D03*
X929400Y1359300D03*
X918900Y1343300D03*
Y1351200D03*
X921500Y1359300D03*
X918000Y1368100D03*
Y1376000D03*
X910100Y1368100D03*
Y1376000D03*
X911000Y1343300D03*
Y1351200D03*
X913600Y1359300D03*
X903100Y1343300D03*
Y1351200D03*
X905700Y1359300D03*
X902200Y1376000D03*
Y1368100D03*
X897800Y1359300D03*
X895200Y1351200D03*
Y1343300D03*
X998600Y1300900D03*
X991500Y1312100D03*
X1020800Y1300400D03*
X991455Y1320416D03*
X996400Y1315900D03*
X996200Y1307800D03*
X1014000Y1300600D03*
X991755Y1327716D03*
X996055Y1324116D03*
X1007100Y1301100D03*
X1011100Y1305300D03*
X1019829Y1306139D03*
X1002700Y1305700D03*
X991800Y1303400D03*
X1000200Y1311700D03*
Y1320500D03*
X1016429Y1333939D03*
X1021829D03*
X1011029D03*
X1005629D03*
X986755Y1323816D03*
X986700Y1307600D03*
X1000200Y1328100D03*
X997900Y1335800D03*
X992500D03*
X997900Y1341200D03*
X992500D03*
X997900Y1346600D03*
X992500D03*
X997900Y1352000D03*
X992500D03*
Y1357400D03*
X997900D03*
X989083Y1387764D03*
X989509Y1393422D03*
X994700Y1385000D03*
X999700Y1374500D03*
X989100Y1381700D03*
X994200Y1362700D03*
X1019829Y1389539D03*
X1013692Y1389688D03*
X1019829Y1361739D03*
X1014306Y1361710D03*
X1008870Y1361681D03*
X1003367Y1361655D03*
X1004217Y1389394D03*
X1008298Y1393071D03*
X994400Y1377300D03*
X999930Y1393070D03*
X999800Y1381600D03*
X999900Y1366800D03*
X994300Y1370100D03*
X989200Y1374800D03*
X988900Y1366900D03*
G54D14*
X848032Y277953D03*
X833859D03*
X848032Y272441D03*
X833859D03*
X862205Y253937D03*
X848032D03*
X833859D03*
X826772Y268504D03*
Y262992D03*
X862205Y292126D03*
X848032D03*
Y286614D03*
X904725Y272835D03*
Y277165D03*
X911811Y282283D03*
X897638Y268110D03*
Y258268D03*
Y263779D03*
X890552Y272835D03*
Y282677D03*
X876378Y253937D03*
X869292Y268504D03*
Y262992D03*
X911811Y300787D03*
Y286614D03*
Y292126D03*
Y296457D03*
X897638Y292126D03*
X890552Y311023D03*
Y291338D03*
X869292Y296850D03*
Y291338D03*
X1119042Y527143D03*
X1109593Y705884D03*
Y720057D03*
Y734230D03*
X1115105Y691711D03*
Y705884D03*
Y720057D03*
Y734230D03*
X1113530Y698797D03*
Y712970D03*
Y727144D03*
X1119042Y698797D03*
Y712970D03*
Y727144D03*
X1109593Y847616D03*
X1115105D03*
X1109593Y861789D03*
X1115105D03*
Y875962D03*
X1113530Y939742D03*
X1119042Y883049D03*
Y939742D03*
G54D15*
X1002362Y284449D03*
X1014960D03*
X1030709D03*
X1043307D03*
X1002362Y261812D03*
X1014960D03*
X1030709D03*
X1043307D03*
X1002362Y278544D03*
X1030709D03*
X1002362Y267717D03*
X1030709D03*
X1002362Y255906D03*
X1030709D03*
X1014960Y278544D03*
X1043307D03*
X1014960Y267717D03*
X1043307D03*
X1014960Y255906D03*
X1043307D03*
X1002362Y290355D03*
X1030709D03*
X1014960D03*
X1043307D03*
G54D16*
G01X106363Y893425D02*
X101763D01*
X96526Y898662D01*
X83500D01*
G01X204190Y455689D02*
X199590D01*
X194353Y460926D01*
X181327D01*
G01X114563Y904041D02*
X194247D01*
X197263Y901025D01*
G01X130601Y1411700D02*
X131074Y1411227D01*
Y1272983D01*
X182345Y1221712D01*
X653488D01*
X758100Y1117100D01*
Y1027000D01*
X761749Y1023351D01*
Y884449D01*
X756200Y878900D01*
X750957D01*
X709612Y837555D01*
Y835212D01*
X709611Y835211D01*
Y783689D01*
X741300Y752000D01*
X776500D01*
X781974Y746526D01*
Y624256D01*
X791530Y614700D01*
G01X124074Y1437200D02*
Y1436716D01*
X124174Y1436616D01*
Y1426712D01*
X138974Y1411912D01*
Y1272969D01*
X184655Y1227288D01*
X679355D01*
X771700Y1134943D01*
Y871900D01*
X783500Y860100D01*
Y758600D01*
X791000Y751100D01*
Y683657D01*
X793700Y680957D01*
Y658800D01*
X789154Y654254D01*
Y621576D01*
X791680Y619050D01*
G01X212390Y466305D02*
X292074D01*
X295090Y463289D01*
G01X1314375Y1424375D02*
X1286575D01*
X1282000Y1419800D01*
X1115100D01*
X1098400Y1403100D01*
X957413D01*
X955504Y1401191D01*
X943983D01*
X942737Y1399945D01*
X935457D01*
X919902Y1415500D01*
X867904D01*
X817204Y1466200D01*
X793700D01*
X770200Y1489700D01*
X723000D01*
X718400Y1494300D01*
X647500D01*
X631800Y1478600D01*
Y1438500D01*
X609864Y1416564D01*
X523455D01*
G01X772601Y1223511D02*
X766601Y1217511D01*
Y1189185D01*
X803427Y1152359D01*
Y994046D01*
X803428Y994045D01*
Y970067D01*
X803427Y970066D01*
Y967310D01*
X806652Y964085D01*
Y933183D01*
X809239Y930596D01*
Y887673D01*
X820700Y876212D01*
Y858209D01*
X820701Y858208D01*
Y855344D01*
X823920Y852125D01*
Y827575D01*
X827533Y823962D01*
Y801151D01*
X825260Y798878D01*
Y658732D01*
X822662Y656134D01*
Y622454D01*
X818166Y617958D01*
Y607481D01*
X825321Y600326D01*
Y541118D01*
X818164Y533961D01*
Y529156D01*
X818163Y529155D01*
Y442417D01*
X810607Y434861D01*
Y279157D01*
X826772Y262992D01*
G01X742880Y1422632D02*
X742881Y1422633D01*
X797534D01*
X808886Y1411281D01*
Y1280186D01*
X758450Y1229750D01*
Y1156150D01*
X777276Y1137324D01*
Y875364D01*
X789077Y863563D01*
Y787466D01*
X801439Y775104D01*
Y762800D01*
X803400Y760839D01*
Y670076D01*
X801439Y668115D01*
Y637839D01*
X799900Y636300D01*
G01X739532Y1425934D02*
X798733D01*
X811886Y1412781D01*
Y1278943D01*
X763601Y1230658D01*
Y1187942D01*
X786800Y1164743D01*
Y1154842D01*
X795276Y1146366D01*
Y990669D01*
X795277Y990668D01*
Y973444D01*
X795276Y973443D01*
Y963932D01*
X798501Y960707D01*
Y930453D01*
X795276Y927228D01*
Y882824D01*
X807399Y870701D01*
Y856412D01*
X807398Y856411D01*
Y849835D01*
X807399Y849834D01*
Y811038D01*
X811372Y807065D01*
Y795900D01*
G01X854354Y319307D02*
Y329461D01*
X840788Y343027D01*
Y443999D01*
X837963Y446824D01*
Y632792D01*
X839412Y634241D01*
Y646645D01*
X839411Y646646D01*
Y648954D01*
X839412Y648955D01*
Y649312D01*
X844175Y654075D01*
Y686756D01*
X847469Y690050D01*
Y833258D01*
X844578Y836149D01*
Y848713D01*
X847076Y851211D01*
Y864591D01*
X838561Y873106D01*
Y926667D01*
X826913Y938316D01*
Y977713D01*
X832200Y983000D01*
Y1143857D01*
X829799Y1146258D01*
Y1150901D01*
X786548Y1194152D01*
Y1207568D01*
X782712Y1211404D01*
G01X842712Y319845D02*
X832136Y330421D01*
Y438864D01*
X829629Y441371D01*
Y460173D01*
X829632Y460176D01*
Y535132D01*
X834662Y540162D01*
Y651162D01*
X841175Y657675D01*
Y687999D01*
X844469Y691293D01*
Y832015D01*
X841578Y834906D01*
Y849957D01*
X844076Y852455D01*
Y863348D01*
X835561Y871863D01*
Y925424D01*
X823912Y937074D01*
X822829Y938157D01*
Y969971D01*
X818004Y974796D01*
Y1151291D01*
X818005Y1151292D01*
Y1158396D01*
X818004Y1158397D01*
Y1158398D01*
X809466Y1166936D01*
X809465D01*
X782712Y1193689D01*
Y1206904D01*
G01X772601Y1219011D02*
X769601Y1216011D01*
Y1190428D01*
X804670Y1155359D01*
X804671D01*
X806427Y1153603D01*
Y995289D01*
X806428Y995288D01*
Y968824D01*
X806427Y968823D01*
Y968553D01*
X809652Y965328D01*
Y934648D01*
X812239Y932061D01*
Y916759D01*
X823700Y905298D01*
Y861128D01*
X823701Y861127D01*
Y856587D01*
X827334Y852954D01*
Y832778D01*
X830533Y829579D01*
Y799908D01*
X828260Y797635D01*
Y657489D01*
X825662Y654891D01*
Y621211D01*
X821166Y616715D01*
Y608724D01*
X828321Y601569D01*
Y539874D01*
X826565Y538118D01*
X826564D01*
X821164Y532718D01*
Y527913D01*
X821163Y527912D01*
Y441174D01*
X813607Y433618D01*
Y281669D01*
X826772Y268504D01*
G01X890552Y291338D02*
X885023Y296867D01*
Y332925D01*
X878764Y339184D01*
Y416449D01*
X867763Y427450D01*
Y433580D01*
X860873Y440470D01*
Y465551D01*
X855839Y470585D01*
Y601379D01*
X860360Y605900D01*
G01X836953Y1023500D02*
Y932520D01*
X841562Y927911D01*
Y905166D01*
X848550Y898178D01*
Y893259D01*
X848175Y892884D01*
Y885122D01*
X848164Y885111D01*
X848175Y885100D01*
Y875624D01*
X860024Y863775D01*
Y852795D01*
X864670Y848149D01*
X864671D01*
X865520Y847300D01*
Y670392D01*
X861198Y666070D01*
Y632811D01*
X853839Y625452D01*
Y469755D01*
X858581Y465013D01*
Y439933D01*
X865763Y432751D01*
Y426621D01*
X876520Y415864D01*
Y332606D01*
X879302Y329824D01*
Y284085D01*
X890552Y272835D01*
G01X842700Y1071900D02*
X842411Y1071611D01*
Y979211D01*
X840070Y976870D01*
Y934230D01*
X843562Y930738D01*
Y905995D01*
X850711Y898846D01*
Y876358D01*
X862024Y865045D01*
Y853624D01*
X865499Y850149D01*
X865500D01*
X867520Y848129D01*
Y669563D01*
X863198Y665241D01*
Y631738D01*
X860360Y628900D01*
Y619092D01*
X860209Y618941D01*
Y610590D01*
X860360Y610439D01*
Y605900D01*
G01X824618Y614617D02*
Y615924D01*
X828662Y619968D01*
Y653648D01*
X831260Y656246D01*
Y796392D01*
X833533Y798665D01*
Y830822D01*
X830334Y834021D01*
Y859119D01*
X831100Y859885D01*
Y864194D01*
X826985Y868309D01*
Y906256D01*
X815239Y918002D01*
Y933305D01*
X812652Y935892D01*
Y966571D01*
X809428Y969795D01*
Y1154844D01*
X809427Y1154845D01*
Y1154846D01*
X805914Y1158359D01*
X805913D01*
X772601Y1191671D01*
Y1214511D01*
G01X827750Y611798D02*
Y614647D01*
X831662Y618559D01*
Y652405D01*
X834260Y655003D01*
Y688970D01*
X836533Y691243D01*
Y832064D01*
X836002Y832595D01*
Y852267D01*
X838500Y854765D01*
Y861038D01*
X829985Y869553D01*
Y923114D01*
X829984Y923115D01*
X815652Y937448D01*
Y967814D01*
X812428Y971038D01*
Y1153601D01*
X812429Y1153602D01*
Y1156086D01*
X812428Y1156087D01*
Y1156088D01*
X807157Y1161359D01*
X807156D01*
X777101Y1191414D01*
Y1223511D01*
G01X807440Y629910D02*
Y647283D01*
X807439Y647284D01*
Y665629D01*
X809400Y667590D01*
Y763325D01*
X807519Y765206D01*
Y777510D01*
X795077Y789952D01*
Y866051D01*
X783276Y877852D01*
Y1141124D01*
X773300Y1151100D01*
Y1159700D01*
G01X802900Y634000D02*
X804439Y635539D01*
Y666872D01*
X806400Y668833D01*
Y762082D01*
X804519Y763963D01*
Y776267D01*
X792077Y788709D01*
Y864808D01*
X780276Y876609D01*
Y1139624D01*
X769800Y1150100D01*
Y1156500D01*
G01X804200Y798200D02*
X798399Y804001D01*
Y846105D01*
X798398Y846106D01*
Y860140D01*
X798399Y860141D01*
Y866972D01*
X786276Y879095D01*
Y977172D01*
X786277Y977173D01*
Y986939D01*
X786276Y986940D01*
Y1142637D01*
X776800Y1152113D01*
Y1169700D01*
G01X808372Y797900D02*
Y805822D01*
X804399Y809795D01*
Y848591D01*
X804398Y848592D01*
Y857654D01*
X804399Y857655D01*
Y869458D01*
X792276Y881581D01*
Y974686D01*
X792277Y974687D01*
Y989425D01*
X792276Y989426D01*
Y1145123D01*
X783400Y1153999D01*
Y1163679D01*
X780722Y1166357D01*
G01X805372Y801700D02*
Y802900D01*
X801399Y806873D01*
Y847348D01*
X801398Y847349D01*
Y858897D01*
X801399Y858898D01*
Y868215D01*
X789276Y880338D01*
Y975929D01*
X789277Y975930D01*
Y988182D01*
X789276Y988183D01*
Y1143880D01*
X780000Y1153156D01*
Y1162800D01*
G01X832800Y1147500D02*
X836953Y1143347D01*
Y1023500D01*
G01X911811Y282283D02*
X912430D01*
X929376Y299229D01*
Y405224D01*
X883001Y451599D01*
Y611911D01*
X883030Y611940D01*
G01X878600Y615600D02*
X880001Y614199D01*
Y450299D01*
X926376Y403924D01*
Y301179D01*
X911811Y286614D01*
G01X879600Y621600D02*
X875599Y617599D01*
Y614358D01*
X877001Y612956D01*
Y448855D01*
X920118Y405738D01*
Y344882D01*
X923376Y341624D01*
Y302983D01*
X912519Y292126D01*
X911811D01*
G01X878400Y626200D02*
X872500Y620300D01*
Y612700D01*
X873901Y611299D01*
Y600551D01*
X870290Y596940D01*
Y486900D01*
X874001Y483189D01*
Y447612D01*
X917118Y404495D01*
Y343639D01*
X920300Y340457D01*
Y304150D01*
X912607Y296457D01*
X911811D01*
G01X1103100Y457300D02*
X1103300Y457500D01*
X1159207D01*
X1185893Y484186D01*
Y736396D01*
X1184261Y738028D01*
X1184260D01*
X1161387Y760901D01*
Y919746D01*
X1138233Y942900D01*
X1122200D01*
X1119042Y939742D01*
G01Y883049D02*
X1122691Y879400D01*
X1139236D01*
X1142651Y875985D01*
X1142761D01*
X1153143Y865603D01*
Y865493D01*
X1153561Y865075D01*
Y756532D01*
X1176929Y733164D01*
Y610650D01*
X1180124Y607455D01*
Y498324D01*
X1177100Y495300D01*
G01X1179129Y672187D02*
X1179784Y672842D01*
Y672896D01*
X1180038Y673150D01*
Y729450D01*
X1179784Y729704D01*
Y733138D01*
X1155561Y757361D01*
Y891359D01*
X1141370Y905550D01*
G01X1155600Y1074500D02*
X1155800Y1074700D01*
Y1152800D01*
X1129000Y1179600D01*
X1110800D01*
X1088000Y1202400D01*
Y1310108D01*
X1075030Y1323078D01*
G01X1724096Y464344D02*
X1737122D01*
X1742359Y459107D01*
X1746959D01*
G01X1821363Y893425D02*
X1816763D01*
X1811526Y898662D01*
X1798500D01*
G01X1829563Y904041D02*
X1912459D01*
X1914500Y902000D01*
G01X1922400Y470400D02*
X1923600Y471600D01*
Y913525D01*
G01X1918800Y1112100D02*
X1923600Y1107300D01*
Y913525D01*
G54D17*
G01X30500Y67000D02*
Y351600D01*
X51500Y372600D01*
Y481500D01*
X95500Y525500D01*
G01X131600Y119100D02*
X126600Y114100D01*
X111100D01*
X95500Y98500D01*
Y72100D01*
X95800Y71800D01*
G01X176506Y539295D02*
X141769Y504558D01*
Y494577D01*
X131278Y484086D01*
X107992D01*
X79581Y455675D01*
Y397946D01*
G01X95500Y525500D02*
Y539500D01*
X143000Y587000D01*
G01X215500Y80500D02*
Y67360D01*
X196051Y47911D01*
Y45700D01*
X185551Y35200D01*
Y21529D01*
G01X125500Y992500D02*
X127500Y994500D01*
Y1026000D01*
X140750Y1039250D01*
G01X254900Y119600D02*
X249700Y114400D01*
X235400D01*
X216700Y95700D01*
Y81700D01*
X215500Y80500D01*
G01X220000Y524000D02*
X219500Y524500D01*
Y553500D01*
X234500Y568500D01*
X247000D01*
X264750Y586250D01*
G01X252000Y992500D02*
Y1026800D01*
X264450Y1039250D01*
G01X379500Y119500D02*
Y118400D01*
X371550Y110450D01*
X355950D01*
X344000Y98500D01*
Y72650D01*
X340650Y69300D01*
G01X390632Y588624D02*
X376316D01*
X344000Y556308D01*
Y525300D01*
G01X376000Y993000D02*
Y1026000D01*
X389250Y1039250D01*
G01X466941Y-145664D02*
Y-225664D01*
G01D02*
X1593241D01*
G01X462941Y-129664D02*
G02I-12000J0D01*
G01X457791D02*
G02I-6850J0D01*
G01X450941Y-145664D02*
Y-113664D01*
G01X466941Y-129664D02*
X434941D01*
G01X466941Y-145664D02*
X1593241D01*
G01X466941Y-181164D02*
X1593241D01*
G01X503900Y119500D02*
X497350Y112950D01*
X482450D01*
X465800Y96300D01*
Y82300D01*
X464000Y80500D01*
G01X517999Y583015D02*
X486488Y551504D01*
X479265D01*
X468000Y540239D01*
Y524355D01*
X464801Y521156D01*
G01X445026Y850100D02*
X440026D01*
G01X569026D02*
X564026D01*
G01X500000Y992000D02*
Y1026000D01*
X513250Y1039250D01*
G01X628000Y119500D02*
X617650Y109150D01*
X603150D01*
X592500Y98500D01*
Y72850D01*
X589150Y69500D01*
G01X637750Y586250D02*
Y585302D01*
X592500Y540052D01*
Y525300D01*
G01X664651Y513000D02*
Y632851D01*
X700960Y669160D01*
Y841138D01*
X759249Y899427D01*
Y1008800D01*
G01X709000Y79500D02*
X714624D01*
X719500Y84376D01*
Y90555D01*
X733569Y104624D01*
Y114089D01*
X746786Y127306D01*
Y131772D01*
X753473Y138459D01*
G01X808395Y454315D02*
Y448486D01*
X793568Y433659D01*
Y294478D01*
X756212Y257122D01*
Y256387D01*
X756208Y256383D01*
Y118138D01*
X724190Y86120D01*
Y53394D01*
X705171Y34375D01*
Y16254D01*
G01X752200Y572300D02*
X745799Y565899D01*
X733400D01*
X724901Y557400D01*
Y533701D01*
X716400Y525200D01*
G01X680526Y850100D02*
X685526D01*
G01X732232Y1477094D02*
X736472D01*
X745032Y1468534D01*
G01X718900Y1472800D02*
X722477D01*
X726771Y1477094D01*
X732232D01*
G01X745032Y1468534D02*
X747632Y1465934D01*
X756332D01*
G01X805741Y-145664D02*
Y-225664D01*
G01X821900Y1173700D02*
X851688Y1143912D01*
Y909212D01*
X865400Y895500D01*
Y884404D01*
X873488Y876316D01*
Y857012D01*
X880000Y850500D01*
Y840976D01*
X879002Y839978D01*
Y817002D01*
X877649Y815649D01*
Y801351D01*
X879000Y800000D01*
Y751500D01*
X876018Y748518D01*
Y629218D01*
X869000Y622200D01*
Y611249D01*
X870400Y609849D01*
Y602000D01*
X864200Y595800D01*
Y492580D01*
X866600Y490180D01*
Y473700D01*
X870400Y469900D01*
Y454315D01*
G01X943241Y-145664D02*
Y-225664D01*
G01X911811Y300787D02*
X911987D01*
X916000Y304800D01*
Y339805D01*
X913618Y342187D01*
Y403044D01*
X870501Y446161D01*
Y454214D01*
X870400Y454315D01*
G01X1058241Y-145664D02*
Y-225664D01*
G01X1225741Y-145664D02*
Y-225664D01*
G01X1157556Y932754D02*
X1164872D01*
X1184778Y912848D01*
G01D02*
X1194262Y903364D01*
X1214864D01*
X1238500Y927000D01*
Y972000D01*
X1260000Y993500D01*
G01X1308000Y35000D02*
Y38000D01*
X1304200Y41800D01*
Y70100D01*
X1302200Y72100D01*
X1298800D01*
X1296102Y74798D01*
Y101148D01*
X1284150Y113100D01*
X1268800D01*
X1262600Y119300D01*
Y119700D01*
G01X1294624Y358802D02*
X1294632Y358810D01*
X1353369D01*
X1360022Y365463D01*
Y394608D01*
X1362514Y397100D01*
G01X1272182Y571361D02*
X1277017Y566526D01*
X1283724D01*
X1296300Y553950D01*
Y517200D01*
X1312000Y501500D01*
G01X1247588Y842190D02*
X1251498Y846100D01*
X1356678D01*
X1362500Y851922D01*
G01X1260000Y993500D02*
Y1022300D01*
X1262400Y1024700D01*
G01X1395741Y-145664D02*
Y-225664D01*
G01X1436000Y48500D02*
Y51000D01*
X1420374Y66626D01*
Y89826D01*
X1396524Y113676D01*
X1394224D01*
X1394200Y113700D01*
G01X1383952Y573102D02*
Y572252D01*
X1394878Y561326D01*
X1412924D01*
X1419900Y554350D01*
Y517600D01*
X1436000Y501500D01*
G01X1386900Y1024600D02*
X1383000Y1020700D01*
Y992900D01*
X1383200Y992700D01*
G01X1511400Y119500D02*
Y118400D01*
X1514950Y114850D01*
X1525650D01*
X1543396Y97104D01*
Y53104D01*
X1557500Y39000D01*
Y35000D01*
G01X1511200Y572300D02*
Y571700D01*
X1516975Y565925D01*
X1532825D01*
X1544500Y554250D01*
Y517500D01*
X1560500Y501500D01*
G01X1511400Y1024600D02*
X1506000Y1019200D01*
Y993000D01*
G01X1593241Y-145664D02*
Y-225664D01*
G01X1621241Y-129664D02*
G02I-12000J0D01*
G01X1616091D02*
G02I-6850J0D01*
G01X1609241Y-145664D02*
Y-113664D01*
G01X1625241Y-129664D02*
X1593241D01*
G01X1635300Y119600D02*
X1646500Y108400D01*
X1655100D01*
X1668512Y94988D01*
Y68988D01*
X1684500Y53000D01*
Y48500D01*
G01Y501500D02*
X1676107Y493107D01*
Y442894D01*
X1705085Y413916D01*
X1769152D01*
X1790265Y392803D01*
X1815946D01*
X1919000Y289749D01*
Y51000D01*
G01X1635100Y1024700D02*
X1631500Y1021100D01*
Y994000D01*
G01X1719726Y1402700D02*
X1713270Y1409156D01*
X1699494D01*
X1676650Y1432000D01*
X1676626D01*
G01X1810426Y1476200D02*
X1807226D01*
X1800326Y1469300D01*
X1794126D01*
X1791426Y1472000D01*
X1786526D01*
X1783726Y1469200D01*
Y1417600D01*
X1775282Y1409156D01*
X1726182D01*
X1719726Y1402700D01*
G01X1662626Y1445500D02*
Y1464000D01*
G01X1676626Y1432000D02*
Y1445700D01*
X1674926Y1447400D01*
G01X1759600Y119500D02*
Y113800D01*
X1792451Y80949D01*
Y65249D01*
X1794300Y63400D01*
G01X1808500Y501500D02*
Y505500D01*
X1794000Y520000D01*
Y552750D01*
X1759750Y587000D01*
G01X1759300Y1024900D02*
X1756000Y1021600D01*
Y993500D01*
G01X1810426Y1476200D02*
X1815726Y1470900D01*
X1824826D01*
G01X1891300Y49400D02*
X1891500Y49600D01*
Y60444D01*
X1883600Y68344D01*
Y75600D01*
X1885413Y77413D01*
X1885508D01*
G01X1853000Y504000D02*
X1874200Y525200D01*
X1878500D01*
X1883300Y530000D01*
G01D02*
X1894887Y541587D01*
Y645387D01*
X1921100Y671600D01*
Y907900D01*
X1920200Y908800D01*
Y935323D01*
X1896101Y959422D01*
Y964435D01*
X1879536Y981000D01*
X1875800D01*
G01X1880500Y540500D02*
X1891887Y551887D01*
Y646630D01*
X1892300Y647043D01*
Y653000D01*
X1918100Y678800D01*
Y905500D01*
X1916900Y906700D01*
Y915400D01*
X1875900Y956400D01*
X1857700D01*
X1843400Y970700D01*
X1827600D01*
G01X1822326Y1481600D02*
Y1478400D01*
X1824826Y1475900D01*
Y1470900D01*
G54D18*
G01X1037550Y1475814D02*
Y1482964D01*
X1020500Y1500014D01*
G01X1297089Y1450307D02*
X1300483Y1446913D01*
Y1437916D01*
X1296374Y1433807D01*
Y1430700D01*
G01X1282374Y1464000D02*
Y1445500D01*
G54D19*
G01X1054918Y1353539D02*
Y1330439D01*
G01D02*
Y1325739D01*
G01Y1358239D02*
Y1353539D01*
G01Y1381339D02*
Y1358239D01*
G01Y1381339D02*
Y1386039D01*
M02*
